FILE_TYPE = MACRO_DRAWING;
SET COLOR_WIRE YELLOW;
SET COLOR_PROP ORANGE;
SET COLOR_DOT WHITE;
SET COLOR_ARC YELLOW;
SET COLOR_BODY GREEN;
SET COLOR_NOTE PURPLE;
SET PROP_DISPLAY VALUE;
SET PAGE_NUMBER P351;
FORCEADD OFFPAGE..1
(-2500 1800);
FORCEPROP 2 LAST $XR0 24 
J 0
(-2751 1800);
DISPLAY 0.638298 (-2751 1800);
PAINT MONO (-2751 1800);
FORCEPROP 2 LAST CDS_LIB standard
J 0
(-2500 1800);
DISPLAY INVISIBLE (-2500 1800);
FORCEPROP 1 LAST OFFPAGE TRUE
J 0
(-2175 1675);
DISPLAY 0.872340 (-2175 1675);
DISPLAY INVISIBLE (-2175 1675);
FORCEPROP 1 LAST COMMENT_BODY TRUE
J 0
(-2375 1700);
DISPLAY 0.872340 (-2375 1700);
PAINT GREEN (-2375 1700);
DISPLAY INVISIBLE (-2375 1700);
FORCEPROP 2 LAST PATH I1
J 0
(-2775 1850);
DISPLAY 1.021277 (-2775 1850);
DISPLAY INVISIBLE (-2775 1850);
FORCEADD TAP..1
R 2
(-1550 925);
FORCEPROP 3 LASTPIN (-1500 925) SIG_NAME P5E_CPU0_P0_TX_DP<3>
J 0
(-1490 935);
DISPLAY 0.659574 (-1490 935);
PAINT MONO (-1490 935);
DISPLAY INVISIBLE (-1490 935);
FORCEPROP 1 LASTPIN (-1500 925) BN 3
J 2
(-1488 933);
DISPLAY 0.680851 (-1488 933);
PAINT GREEN (-1488 933);
FORCEPROP 2 LAST CDS_LIB standard
J 0
(-1550 925);
DISPLAY INVISIBLE (-1550 925);
FORCEPROP 1 LAST BODY_TYPE PLUMBING
J 2
(-1550 975);
DISPLAY 0.872340 (-1550 975);
PAINT GREEN (-1550 975);
DISPLAY INVISIBLE (-1550 975);
FORCEPROP 1 LAST HDL_TAP TRUE
J 2
(-1875 800);
DISPLAY 0.872340 (-1875 800);
DISPLAY INVISIBLE (-1875 800);
FORCEPROP 1 LAST PATH I10
J 2
(-1548 925);
DISPLAY 0.872340 (-1548 925);
PAINT GREEN (-1548 925);
DISPLAY INVISIBLE (-1548 925);
FORCEADD TAP..1
(175 2700);
FORCEPROP 3 LASTPIN (125 2700) SIG_NAME P5E_CPU0_P0_TX_C_DP<10>
J 0
(135 2710);
DISPLAY 0.659574 (135 2710);
PAINT MONO (135 2710);
DISPLAY INVISIBLE (135 2710);
FORCEPROP 1 LASTPIN (125 2700) BN 10
J 0
(113 2708);
DISPLAY 0.680851 (113 2708);
PAINT GREEN (113 2708);
FORCEPROP 2 LAST CDS_LIB standard
J 0
(175 2700);
DISPLAY INVISIBLE (175 2700);
FORCEPROP 1 LAST BODY_TYPE PLUMBING
J 0
(175 2750);
DISPLAY 0.872340 (175 2750);
PAINT GREEN (175 2750);
DISPLAY INVISIBLE (175 2750);
FORCEPROP 1 LAST HDL_TAP TRUE
J 0
(500 2575);
DISPLAY 0.872340 (500 2575);
DISPLAY INVISIBLE (500 2575);
FORCEPROP 1 LAST PATH I100
J 0
(173 2700);
DISPLAY 0.872340 (173 2700);
PAINT GREEN (173 2700);
DISPLAY INVISIBLE (173 2700);
FORCEADD TAP..1
(175 3100);
FORCEPROP 3 LASTPIN (125 3100) SIG_NAME P5E_CPU0_P0_TX_C_DP<12>
J 0
(135 3110);
DISPLAY 0.659574 (135 3110);
PAINT MONO (135 3110);
DISPLAY INVISIBLE (135 3110);
FORCEPROP 1 LASTPIN (125 3100) BN 12
J 0
(113 3108);
DISPLAY 0.680851 (113 3108);
PAINT GREEN (113 3108);
FORCEPROP 2 LAST CDS_LIB standard
J 0
(175 3100);
DISPLAY INVISIBLE (175 3100);
FORCEPROP 1 LAST BODY_TYPE PLUMBING
J 0
(175 3150);
DISPLAY 0.872340 (175 3150);
PAINT GREEN (175 3150);
DISPLAY INVISIBLE (175 3150);
FORCEPROP 1 LAST HDL_TAP TRUE
J 0
(500 2975);
DISPLAY 0.872340 (500 2975);
DISPLAY INVISIBLE (500 2975);
FORCEPROP 1 LAST PATH I101
J 0
(173 3100);
DISPLAY 0.872340 (173 3100);
PAINT GREEN (173 3100);
DISPLAY INVISIBLE (173 3100);
FORCEADD TAP..1
(175 3300);
FORCEPROP 3 LASTPIN (125 3300) SIG_NAME P5E_CPU0_P0_TX_C_DP<13>
J 0
(135 3310);
DISPLAY 0.659574 (135 3310);
PAINT MONO (135 3310);
DISPLAY INVISIBLE (135 3310);
FORCEPROP 1 LASTPIN (125 3300) BN 13
J 0
(113 3308);
DISPLAY 0.680851 (113 3308);
PAINT GREEN (113 3308);
FORCEPROP 2 LAST CDS_LIB standard
J 0
(175 3300);
DISPLAY INVISIBLE (175 3300);
FORCEPROP 1 LAST BODY_TYPE PLUMBING
J 0
(175 3350);
DISPLAY 0.872340 (175 3350);
PAINT GREEN (175 3350);
DISPLAY INVISIBLE (175 3350);
FORCEPROP 1 LAST HDL_TAP TRUE
J 0
(500 3175);
DISPLAY 0.872340 (500 3175);
DISPLAY INVISIBLE (500 3175);
FORCEPROP 1 LAST PATH I102
J 0
(173 3300);
DISPLAY 0.872340 (173 3300);
PAINT GREEN (173 3300);
DISPLAY INVISIBLE (173 3300);
FORCEADD TAP..1
(175 3500);
FORCEPROP 3 LASTPIN (125 3500) SIG_NAME P5E_CPU0_P0_TX_C_DP<14>
J 0
(135 3510);
DISPLAY 0.659574 (135 3510);
PAINT MONO (135 3510);
DISPLAY INVISIBLE (135 3510);
FORCEPROP 1 LASTPIN (125 3500) BN 14
J 0
(113 3508);
DISPLAY 0.680851 (113 3508);
PAINT GREEN (113 3508);
FORCEPROP 2 LAST CDS_LIB standard
J 0
(175 3500);
DISPLAY INVISIBLE (175 3500);
FORCEPROP 1 LAST BODY_TYPE PLUMBING
J 0
(175 3550);
DISPLAY 0.872340 (175 3550);
PAINT GREEN (175 3550);
DISPLAY INVISIBLE (175 3550);
FORCEPROP 1 LAST HDL_TAP TRUE
J 0
(500 3375);
DISPLAY 0.872340 (500 3375);
DISPLAY INVISIBLE (500 3375);
FORCEPROP 1 LAST PATH I103
J 0
(173 3500);
DISPLAY 0.872340 (173 3500);
PAINT GREEN (173 3500);
DISPLAY INVISIBLE (173 3500);
FORCEADD TAP..1
(175 3700);
FORCEPROP 3 LASTPIN (125 3700) SIG_NAME P5E_CPU0_P0_TX_C_DP<15>
J 0
(135 3710);
DISPLAY 0.659574 (135 3710);
PAINT MONO (135 3710);
DISPLAY INVISIBLE (135 3710);
FORCEPROP 1 LASTPIN (125 3700) BN 15
J 0
(113 3708);
DISPLAY 0.680851 (113 3708);
PAINT GREEN (113 3708);
FORCEPROP 2 LAST CDS_LIB standard
J 0
(175 3700);
DISPLAY INVISIBLE (175 3700);
FORCEPROP 1 LAST BODY_TYPE PLUMBING
J 0
(175 3750);
DISPLAY 0.872340 (175 3750);
PAINT GREEN (175 3750);
DISPLAY INVISIBLE (175 3750);
FORCEPROP 1 LAST HDL_TAP TRUE
J 0
(500 3575);
DISPLAY 0.872340 (500 3575);
DISPLAY INVISIBLE (500 3575);
FORCEPROP 1 LAST PATH I104
J 0
(173 3700);
DISPLAY 0.872340 (173 3700);
PAINT GREEN (173 3700);
DISPLAY INVISIBLE (173 3700);
FORCEADD OFFPAGE..2
(1175 3725);
FORCEPROP 2 LAST $XR0 273 
J 0
(1364 3725);
DISPLAY 0.638298 (1364 3725);
PAINT MONO (1364 3725);
FORCEPROP 2 LAST CDS_LIB standard
J 0
(1175 3725);
DISPLAY INVISIBLE (1175 3725);
FORCEPROP 1 LAST OFFPAGE TRUE
J 0
(1500 3600);
DISPLAY 0.872340 (1500 3600);
DISPLAY INVISIBLE (1500 3600);
FORCEPROP 1 LAST COMMENT_BODY TRUE
J 0
(1130 3630);
DISPLAY 0.872340 (1130 3630);
PAINT GREEN (1130 3630);
DISPLAY INVISIBLE (1130 3630);
FORCEPROP 2 LAST PATH I105
J 0
(1375 3775);
DISPLAY 1.021277 (1375 3775);
DISPLAY INVISIBLE (1375 3775);
FORCEADD OFFPAGE..2
(1175 3775);
FORCEPROP 2 LAST $XR0 273 
J 0
(1364 3775);
DISPLAY 0.638298 (1364 3775);
PAINT MONO (1364 3775);
FORCEPROP 2 LAST CDS_LIB standard
J 0
(1175 3775);
DISPLAY INVISIBLE (1175 3775);
FORCEPROP 1 LAST OFFPAGE TRUE
J 0
(1500 3650);
DISPLAY 0.872340 (1500 3650);
DISPLAY INVISIBLE (1500 3650);
FORCEPROP 1 LAST COMMENT_BODY TRUE
J 0
(1130 3680);
DISPLAY 0.872340 (1130 3680);
PAINT GREEN (1130 3680);
DISPLAY INVISIBLE (1130 3680);
FORCEPROP 2 LAST PATH I106
J 0
(1375 3825);
DISPLAY 1.021277 (1375 3825);
DISPLAY INVISIBLE (1375 3825);
FORCEADD OFFPAGE..1
(2050 3725);
FORCEPROP 2 LAST $XR0 24 
J 0
(1829 3725);
DISPLAY 0.638298 (1829 3725);
PAINT MONO (1829 3725);
FORCEPROP 2 LAST CDS_LIB standard
J 0
(2050 3725);
DISPLAY INVISIBLE (2050 3725);
FORCEPROP 1 LAST OFFPAGE TRUE
J 0
(2375 3600);
DISPLAY 0.872340 (2375 3600);
DISPLAY INVISIBLE (2375 3600);
FORCEPROP 1 LAST COMMENT_BODY TRUE
J 0
(2175 3625);
DISPLAY 0.872340 (2175 3625);
PAINT GREEN (2175 3625);
DISPLAY INVISIBLE (2175 3625);
FORCEPROP 2 LAST PATH I107
J 0
(1800 3775);
DISPLAY 1.021277 (1800 3775);
DISPLAY INVISIBLE (1800 3775);
FORCEADD OFFPAGE..1
(2050 3775);
FORCEPROP 2 LAST $XR0 24 
J 0
(1829 3775);
DISPLAY 0.638298 (1829 3775);
PAINT MONO (1829 3775);
FORCEPROP 2 LAST CDS_LIB standard
J 0
(2050 3775);
DISPLAY INVISIBLE (2050 3775);
FORCEPROP 1 LAST OFFPAGE TRUE
J 0
(2375 3650);
DISPLAY 0.872340 (2375 3650);
DISPLAY INVISIBLE (2375 3650);
FORCEPROP 1 LAST COMMENT_BODY TRUE
J 0
(2175 3675);
DISPLAY 0.872340 (2175 3675);
PAINT GREEN (2175 3675);
DISPLAY INVISIBLE (2175 3675);
FORCEPROP 2 LAST PATH I108
J 0
(1800 3825);
DISPLAY 1.021277 (1800 3825);
DISPLAY INVISIBLE (1800 3825);
FORCEADD TAP..1
R 2
(3000 525);
FORCEPROP 3 LASTPIN (3050 525) SIG_NAME P5E_CPU0_P1_TX_DP<1>
J 0
(3060 535);
DISPLAY 0.659574 (3060 535);
PAINT MONO (3060 535);
DISPLAY INVISIBLE (3060 535);
FORCEPROP 1 LASTPIN (3050 525) BN 1
J 2
(3062 533);
DISPLAY 0.680851 (3062 533);
PAINT GREEN (3062 533);
FORCEPROP 2 LAST CDS_LIB standard
J 0
(3000 525);
DISPLAY INVISIBLE (3000 525);
FORCEPROP 1 LAST BODY_TYPE PLUMBING
J 2
(3000 575);
DISPLAY 0.872340 (3000 575);
PAINT GREEN (3000 575);
DISPLAY INVISIBLE (3000 575);
FORCEPROP 1 LAST HDL_TAP TRUE
J 2
(2675 400);
DISPLAY 0.872340 (2675 400);
DISPLAY INVISIBLE (2675 400);
FORCEPROP 1 LAST PATH I109
J 2
(3002 525);
DISPLAY 0.872340 (3002 525);
PAINT GREEN (3002 525);
DISPLAY INVISIBLE (3002 525);
FORCEADD TAP..1
R 2
(-1550 1125);
FORCEPROP 3 LASTPIN (-1500 1125) SIG_NAME P5E_CPU0_P0_TX_DP<4>
J 0
(-1490 1135);
DISPLAY 0.659574 (-1490 1135);
PAINT MONO (-1490 1135);
DISPLAY INVISIBLE (-1490 1135);
FORCEPROP 1 LASTPIN (-1500 1125) BN 4
J 2
(-1488 1133);
DISPLAY 0.680851 (-1488 1133);
PAINT GREEN (-1488 1133);
FORCEPROP 2 LAST CDS_LIB standard
J 0
(-1550 1125);
DISPLAY INVISIBLE (-1550 1125);
FORCEPROP 1 LAST BODY_TYPE PLUMBING
J 2
(-1550 1175);
DISPLAY 0.872340 (-1550 1175);
PAINT GREEN (-1550 1175);
DISPLAY INVISIBLE (-1550 1175);
FORCEPROP 1 LAST HDL_TAP TRUE
J 2
(-1875 1000);
DISPLAY 0.872340 (-1875 1000);
DISPLAY INVISIBLE (-1875 1000);
FORCEPROP 1 LAST PATH I11
J 2
(-1548 1125);
DISPLAY 0.872340 (-1548 1125);
PAINT GREEN (-1548 1125);
DISPLAY INVISIBLE (-1548 1125);
FORCEADD TAP..1
R 2
(3000 325);
FORCEPROP 3 LASTPIN (3050 325) SIG_NAME P5E_CPU0_P1_TX_DP<0>
J 0
(3060 335);
DISPLAY 0.659574 (3060 335);
PAINT MONO (3060 335);
DISPLAY INVISIBLE (3060 335);
FORCEPROP 1 LASTPIN (3050 325) BN 0
J 2
(3062 333);
DISPLAY 0.680851 (3062 333);
PAINT GREEN (3062 333);
FORCEPROP 2 LAST CDS_LIB standard
J 0
(3000 325);
DISPLAY INVISIBLE (3000 325);
FORCEPROP 1 LAST BODY_TYPE PLUMBING
J 2
(3000 375);
DISPLAY 0.872340 (3000 375);
PAINT GREEN (3000 375);
DISPLAY INVISIBLE (3000 375);
FORCEPROP 1 LAST HDL_TAP TRUE
J 2
(2675 200);
DISPLAY 0.872340 (2675 200);
DISPLAY INVISIBLE (2675 200);
FORCEPROP 1 LAST PATH I110
J 2
(3002 325);
DISPLAY 0.872340 (3002 325);
PAINT GREEN (3002 325);
DISPLAY INVISIBLE (3002 325);
FORCEADD TAP..1
R 2
(3000 925);
FORCEPROP 3 LASTPIN (3050 925) SIG_NAME P5E_CPU0_P1_TX_DP<3>
J 0
(3060 935);
DISPLAY 0.659574 (3060 935);
PAINT MONO (3060 935);
DISPLAY INVISIBLE (3060 935);
FORCEPROP 1 LASTPIN (3050 925) BN 3
J 2
(3062 933);
DISPLAY 0.680851 (3062 933);
PAINT GREEN (3062 933);
FORCEPROP 2 LAST CDS_LIB standard
J 0
(3000 925);
DISPLAY INVISIBLE (3000 925);
FORCEPROP 1 LAST BODY_TYPE PLUMBING
J 2
(3000 975);
DISPLAY 0.872340 (3000 975);
PAINT GREEN (3000 975);
DISPLAY INVISIBLE (3000 975);
FORCEPROP 1 LAST HDL_TAP TRUE
J 2
(2675 800);
DISPLAY 0.872340 (2675 800);
DISPLAY INVISIBLE (2675 800);
FORCEPROP 1 LAST PATH I111
J 2
(3002 925);
DISPLAY 0.872340 (3002 925);
PAINT GREEN (3002 925);
DISPLAY INVISIBLE (3002 925);
FORCEADD TAP..1
R 2
(3000 725);
FORCEPROP 3 LASTPIN (3050 725) SIG_NAME P5E_CPU0_P1_TX_DP<2>
J 0
(3060 735);
DISPLAY 0.659574 (3060 735);
PAINT MONO (3060 735);
DISPLAY INVISIBLE (3060 735);
FORCEPROP 1 LASTPIN (3050 725) BN 2
J 2
(3062 733);
DISPLAY 0.680851 (3062 733);
PAINT GREEN (3062 733);
FORCEPROP 2 LAST CDS_LIB standard
J 0
(3000 725);
DISPLAY INVISIBLE (3000 725);
FORCEPROP 1 LAST BODY_TYPE PLUMBING
J 2
(3000 775);
DISPLAY 0.872340 (3000 775);
PAINT GREEN (3000 775);
DISPLAY INVISIBLE (3000 775);
FORCEPROP 1 LAST HDL_TAP TRUE
J 2
(2675 600);
DISPLAY 0.872340 (2675 600);
DISPLAY INVISIBLE (2675 600);
FORCEPROP 1 LAST PATH I112
J 2
(3002 725);
DISPLAY 0.872340 (3002 725);
PAINT GREEN (3002 725);
DISPLAY INVISIBLE (3002 725);
FORCEADD TAP..1
R 2
(3000 1525);
FORCEPROP 3 LASTPIN (3050 1525) SIG_NAME P5E_CPU0_P1_TX_DP<6>
J 0
(3060 1535);
DISPLAY 0.659574 (3060 1535);
PAINT MONO (3060 1535);
DISPLAY INVISIBLE (3060 1535);
FORCEPROP 1 LASTPIN (3050 1525) BN 6
J 2
(3062 1533);
DISPLAY 0.680851 (3062 1533);
PAINT GREEN (3062 1533);
FORCEPROP 2 LAST CDS_LIB standard
J 0
(3000 1525);
DISPLAY INVISIBLE (3000 1525);
FORCEPROP 1 LAST BODY_TYPE PLUMBING
J 2
(3000 1575);
DISPLAY 0.872340 (3000 1575);
PAINT GREEN (3000 1575);
DISPLAY INVISIBLE (3000 1575);
FORCEPROP 1 LAST HDL_TAP TRUE
J 2
(2675 1400);
DISPLAY 0.872340 (2675 1400);
DISPLAY INVISIBLE (2675 1400);
FORCEPROP 1 LAST PATH I113
J 2
(3002 1525);
DISPLAY 0.872340 (3002 1525);
PAINT GREEN (3002 1525);
DISPLAY INVISIBLE (3002 1525);
FORCEADD TAP..1
R 2
(3000 1325);
FORCEPROP 3 LASTPIN (3050 1325) SIG_NAME P5E_CPU0_P1_TX_DP<5>
J 0
(3060 1335);
DISPLAY 0.659574 (3060 1335);
PAINT MONO (3060 1335);
DISPLAY INVISIBLE (3060 1335);
FORCEPROP 1 LASTPIN (3050 1325) BN 5
J 2
(3062 1333);
DISPLAY 0.680851 (3062 1333);
PAINT GREEN (3062 1333);
FORCEPROP 2 LAST CDS_LIB standard
J 0
(3000 1325);
DISPLAY INVISIBLE (3000 1325);
FORCEPROP 1 LAST BODY_TYPE PLUMBING
J 2
(3000 1375);
DISPLAY 0.872340 (3000 1375);
PAINT GREEN (3000 1375);
DISPLAY INVISIBLE (3000 1375);
FORCEPROP 1 LAST HDL_TAP TRUE
J 2
(2675 1200);
DISPLAY 0.872340 (2675 1200);
DISPLAY INVISIBLE (2675 1200);
FORCEPROP 1 LAST PATH I114
J 2
(3002 1325);
DISPLAY 0.872340 (3002 1325);
PAINT GREEN (3002 1325);
DISPLAY INVISIBLE (3002 1325);
FORCEADD TAP..1
R 2
(3000 1125);
FORCEPROP 3 LASTPIN (3050 1125) SIG_NAME P5E_CPU0_P1_TX_DP<4>
J 0
(3060 1135);
DISPLAY 0.659574 (3060 1135);
PAINT MONO (3060 1135);
DISPLAY INVISIBLE (3060 1135);
FORCEPROP 1 LASTPIN (3050 1125) BN 4
J 2
(3062 1133);
DISPLAY 0.680851 (3062 1133);
PAINT GREEN (3062 1133);
FORCEPROP 2 LAST CDS_LIB standard
J 0
(3000 1125);
DISPLAY INVISIBLE (3000 1125);
FORCEPROP 1 LAST BODY_TYPE PLUMBING
J 2
(3000 1175);
DISPLAY 0.872340 (3000 1175);
PAINT GREEN (3000 1175);
DISPLAY INVISIBLE (3000 1175);
FORCEPROP 1 LAST HDL_TAP TRUE
J 2
(2675 1000);
DISPLAY 0.872340 (2675 1000);
DISPLAY INVISIBLE (2675 1000);
FORCEPROP 1 LAST PATH I115
J 2
(3002 1125);
DISPLAY 0.872340 (3002 1125);
PAINT GREEN (3002 1125);
DISPLAY INVISIBLE (3002 1125);
FORCEADD TAP..1
R 2
(3000 1725);
FORCEPROP 3 LASTPIN (3050 1725) SIG_NAME P5E_CPU0_P1_TX_DP<7>
J 0
(3060 1735);
DISPLAY 0.659574 (3060 1735);
PAINT MONO (3060 1735);
DISPLAY INVISIBLE (3060 1735);
FORCEPROP 1 LASTPIN (3050 1725) BN 7
J 2
(3062 1733);
DISPLAY 0.680851 (3062 1733);
PAINT GREEN (3062 1733);
FORCEPROP 2 LAST CDS_LIB standard
J 0
(3000 1725);
DISPLAY INVISIBLE (3000 1725);
FORCEPROP 1 LAST BODY_TYPE PLUMBING
J 2
(3000 1775);
DISPLAY 0.872340 (3000 1775);
PAINT GREEN (3000 1775);
DISPLAY INVISIBLE (3000 1775);
FORCEPROP 1 LAST HDL_TAP TRUE
J 2
(2675 1600);
DISPLAY 0.872340 (2675 1600);
DISPLAY INVISIBLE (2675 1600);
FORCEPROP 1 LAST PATH I116
J 2
(3002 1725);
DISPLAY 0.872340 (3002 1725);
PAINT GREEN (3002 1725);
DISPLAY INVISIBLE (3002 1725);
FORCEADD TAP..1
R 2
(3250 375);
FORCEPROP 3 LASTPIN (3300 375) SIG_NAME P5E_CPU0_P1_TX_DN<0>
J 0
(3310 385);
DISPLAY 0.659574 (3310 385);
PAINT MONO (3310 385);
DISPLAY INVISIBLE (3310 385);
FORCEPROP 1 LASTPIN (3300 375) BN 0
J 2
(3312 383);
DISPLAY 0.680851 (3312 383);
PAINT GREEN (3312 383);
FORCEPROP 2 LAST CDS_LIB standard
J 0
(3250 375);
DISPLAY INVISIBLE (3250 375);
FORCEPROP 1 LAST BODY_TYPE PLUMBING
J 2
(3250 425);
DISPLAY 0.872340 (3250 425);
PAINT GREEN (3250 425);
DISPLAY INVISIBLE (3250 425);
FORCEPROP 1 LAST HDL_TAP TRUE
J 2
(2925 250);
DISPLAY 0.872340 (2925 250);
DISPLAY INVISIBLE (2925 250);
FORCEPROP 1 LAST PATH I117
J 2
(3252 375);
DISPLAY 0.872340 (3252 375);
PAINT GREEN (3252 375);
DISPLAY INVISIBLE (3252 375);
FORCEADD TAP..1
R 2
(3250 575);
FORCEPROP 3 LASTPIN (3300 575) SIG_NAME P5E_CPU0_P1_TX_DN<1>
J 0
(3310 585);
DISPLAY 0.659574 (3310 585);
PAINT MONO (3310 585);
DISPLAY INVISIBLE (3310 585);
FORCEPROP 1 LASTPIN (3300 575) BN 1
J 2
(3312 583);
DISPLAY 0.680851 (3312 583);
PAINT GREEN (3312 583);
FORCEPROP 2 LAST CDS_LIB standard
J 0
(3250 575);
DISPLAY INVISIBLE (3250 575);
FORCEPROP 1 LAST BODY_TYPE PLUMBING
J 2
(3250 625);
DISPLAY 0.872340 (3250 625);
PAINT GREEN (3250 625);
DISPLAY INVISIBLE (3250 625);
FORCEPROP 1 LAST HDL_TAP TRUE
J 2
(2925 450);
DISPLAY 0.872340 (2925 450);
DISPLAY INVISIBLE (2925 450);
FORCEPROP 1 LAST PATH I118
J 2
(3252 575);
DISPLAY 0.872340 (3252 575);
PAINT GREEN (3252 575);
DISPLAY INVISIBLE (3252 575);
FORCEADD TAP..1
R 2
(3250 775);
FORCEPROP 3 LASTPIN (3300 775) SIG_NAME P5E_CPU0_P1_TX_DN<2>
J 0
(3310 785);
DISPLAY 0.659574 (3310 785);
PAINT MONO (3310 785);
DISPLAY INVISIBLE (3310 785);
FORCEPROP 1 LASTPIN (3300 775) BN 2
J 2
(3312 783);
DISPLAY 0.680851 (3312 783);
PAINT GREEN (3312 783);
FORCEPROP 2 LAST CDS_LIB standard
J 0
(3250 775);
DISPLAY INVISIBLE (3250 775);
FORCEPROP 1 LAST BODY_TYPE PLUMBING
J 2
(3250 825);
DISPLAY 0.872340 (3250 825);
PAINT GREEN (3250 825);
DISPLAY INVISIBLE (3250 825);
FORCEPROP 1 LAST HDL_TAP TRUE
J 2
(2925 650);
DISPLAY 0.872340 (2925 650);
DISPLAY INVISIBLE (2925 650);
FORCEPROP 1 LAST PATH I119
J 2
(3252 775);
DISPLAY 0.872340 (3252 775);
PAINT GREEN (3252 775);
DISPLAY INVISIBLE (3252 775);
FORCEADD TAP..1
R 2
(-1300 775);
FORCEPROP 3 LASTPIN (-1250 775) SIG_NAME P5E_CPU0_P0_TX_DN<2>
J 0
(-1240 785);
DISPLAY 0.659574 (-1240 785);
PAINT MONO (-1240 785);
DISPLAY INVISIBLE (-1240 785);
FORCEPROP 1 LASTPIN (-1250 775) BN 2
J 2
(-1238 783);
DISPLAY 0.680851 (-1238 783);
PAINT GREEN (-1238 783);
FORCEPROP 2 LAST CDS_LIB standard
J 0
(-1300 775);
DISPLAY INVISIBLE (-1300 775);
FORCEPROP 1 LAST BODY_TYPE PLUMBING
J 2
(-1300 825);
DISPLAY 0.872340 (-1300 825);
PAINT GREEN (-1300 825);
DISPLAY INVISIBLE (-1300 825);
FORCEPROP 1 LAST HDL_TAP TRUE
J 2
(-1625 650);
DISPLAY 0.872340 (-1625 650);
DISPLAY INVISIBLE (-1625 650);
FORCEPROP 1 LAST PATH I12
J 2
(-1298 775);
DISPLAY 0.872340 (-1298 775);
PAINT GREEN (-1298 775);
DISPLAY INVISIBLE (-1298 775);
FORCEADD TAP..1
R 2
(3250 975);
FORCEPROP 3 LASTPIN (3300 975) SIG_NAME P5E_CPU0_P1_TX_DN<3>
J 0
(3310 985);
DISPLAY 0.659574 (3310 985);
PAINT MONO (3310 985);
DISPLAY INVISIBLE (3310 985);
FORCEPROP 1 LASTPIN (3300 975) BN 3
J 2
(3312 983);
DISPLAY 0.680851 (3312 983);
PAINT GREEN (3312 983);
FORCEPROP 2 LAST CDS_LIB standard
J 0
(3250 975);
DISPLAY INVISIBLE (3250 975);
FORCEPROP 1 LAST BODY_TYPE PLUMBING
J 2
(3250 1025);
DISPLAY 0.872340 (3250 1025);
PAINT GREEN (3250 1025);
DISPLAY INVISIBLE (3250 1025);
FORCEPROP 1 LAST HDL_TAP TRUE
J 2
(2925 850);
DISPLAY 0.872340 (2925 850);
DISPLAY INVISIBLE (2925 850);
FORCEPROP 1 LAST PATH I120
J 2
(3252 975);
DISPLAY 0.872340 (3252 975);
PAINT GREEN (3252 975);
DISPLAY INVISIBLE (3252 975);
FORCEADD Q_CAP_DIFFBUS..2
R 2
(3975 325);
FORCEPROP 1 LAST LOCATION C965
J 2
(4209 342);
DISPLAY 0.723404 (4209 342);
PAINT GREEN (4209 342);
FORCEPROP 2 LAST $SEC 1
J 2
(4150 400);
DISPLAY 0.680851 (4150 400);
PAINT MONO (4150 400);
DISPLAY INVISIBLE (4150 400);
FORCEPROP 2 LAST CDS_SEC 1
J 2
(4150 400);
DISPLAY 0.680851 (4150 400);
DISPLAY INVISIBLE (4150 400);
FORCEPROP 2 LASTPIN (4050 325) $PN 1
J 0
(4060 335);
DISPLAY 0.808511 (4060 335);
FORCEPROP 2 LASTPIN (3900 325) $PN 2
J 2
(3890 335);
DISPLAY 0.808511 (3890 335);
FORCEPROP 2 LAST VALUE DIFF BUS_0.22UF
J 2
(3825 325);
DISPLAY 0.553191 (3825 325);
FORCEPROP 1 LAST PIN_NAMES_ROTATE TRUE
J 2
(3975 325);
DISPLAY 0.489362 (3975 325);
PAINT GREEN (3975 325);
DISPLAY INVISIBLE (3975 325);
FORCEPROP 2 LAST CDS_LIB pure_quanta
J 2
(3975 325);
DISPLAY INVISIBLE (3975 325);
FORCEPROP 1 LAST CDS_LMAN_SYM_OUTLINE -25,50,25,-50
J 2
(3975 325);
DISPLAY 0.468085 (3975 325);
PAINT GREEN (3975 325);
DISPLAY INVISIBLE (3975 325);
FORCEPROP 2 LAST VOLTAGE 6.3V
J 2
(3625 375);
DISPLAY 0.553191 (3625 375);
DISPLAY INVISIBLE (3625 375);
FORCEPROP 1 LAST MATERIAL X6S
J 2
(3984 404);
DISPLAY 0.574468 (3984 404);
PAINT GREEN (3984 404);
DISPLAY INVISIBLE (3984 404);
FORCEPROP 2 LAST PACK_TYPE C0201
J 2
(3800 375);
DISPLAY 0.553191 (3800 375);
DISPLAY INVISIBLE (3800 375);
FORCEPROP 2 LAST TOLERANCE 20%
J 2
(3900 375);
DISPLAY 0.553191 (3900 375);
DISPLAY INVISIBLE (3900 375);
FORCEPROP 1 LAST PART_NUMBER SP_CH4221MEE01
J 2
(3859 413);
DISPLAY 0.574468 (3859 413);
PAINT GREEN (3859 413);
DISPLAY INVISIBLE (3859 413);
FORCEPROP 1 LAST LOCATION C965
J 0
(4225 400);
DISPLAY 1.021277 (4225 400);
DISPLAY INVISIBLE (4225 400);
FORCEPROP 1 LAST PATH I121
J 2
(3975 325);
DISPLAY 0.723404 (3975 325);
DISPLAY INVISIBLE (3975 325);
FORCEADD Q_CAP_DIFFBUS..2
R 2
(3975 375);
FORCEPROP 1 LAST LOCATION C964
J 2
(4209 392);
DISPLAY 0.723404 (4209 392);
PAINT GREEN (4209 392);
FORCEPROP 2 LAST $SEC 1
J 2
(4150 450);
DISPLAY 0.680851 (4150 450);
PAINT MONO (4150 450);
DISPLAY INVISIBLE (4150 450);
FORCEPROP 2 LAST CDS_SEC 1
J 2
(4150 450);
DISPLAY 0.680851 (4150 450);
DISPLAY INVISIBLE (4150 450);
FORCEPROP 2 LASTPIN (4050 375) $PN 1
J 0
(4060 385);
DISPLAY 0.808511 (4060 385);
FORCEPROP 2 LASTPIN (3900 375) $PN 2
J 2
(3890 385);
DISPLAY 0.808511 (3890 385);
FORCEPROP 2 LAST VALUE DIFF BUS_0.22UF
J 2
(3825 375);
DISPLAY 0.553191 (3825 375);
FORCEPROP 1 LAST PIN_NAMES_ROTATE TRUE
J 2
(3975 375);
DISPLAY 0.489362 (3975 375);
PAINT GREEN (3975 375);
DISPLAY INVISIBLE (3975 375);
FORCEPROP 2 LAST CDS_LIB pure_quanta
J 2
(3975 375);
DISPLAY INVISIBLE (3975 375);
FORCEPROP 1 LAST CDS_LMAN_SYM_OUTLINE -25,50,25,-50
J 2
(3975 375);
DISPLAY 0.468085 (3975 375);
PAINT GREEN (3975 375);
DISPLAY INVISIBLE (3975 375);
FORCEPROP 2 LAST VOLTAGE 6.3V
J 2
(3625 425);
DISPLAY 0.553191 (3625 425);
DISPLAY INVISIBLE (3625 425);
FORCEPROP 1 LAST MATERIAL X6S
J 2
(3984 454);
DISPLAY 0.574468 (3984 454);
PAINT GREEN (3984 454);
DISPLAY INVISIBLE (3984 454);
FORCEPROP 2 LAST PACK_TYPE C0201
J 2
(3800 425);
DISPLAY 0.553191 (3800 425);
DISPLAY INVISIBLE (3800 425);
FORCEPROP 2 LAST TOLERANCE 20%
J 2
(3900 425);
DISPLAY 0.553191 (3900 425);
DISPLAY INVISIBLE (3900 425);
FORCEPROP 1 LAST PART_NUMBER SP_CH4221MEE01
J 2
(3859 463);
DISPLAY 0.574468 (3859 463);
PAINT GREEN (3859 463);
DISPLAY INVISIBLE (3859 463);
FORCEPROP 1 LAST LOCATION C964
J 0
(4225 450);
DISPLAY 1.021277 (4225 450);
DISPLAY INVISIBLE (4225 450);
FORCEPROP 1 LAST PATH I122
J 2
(3975 375);
DISPLAY 0.723404 (3975 375);
DISPLAY INVISIBLE (3975 375);
FORCEADD Q_CAP_DIFFBUS..2
R 2
(3975 525);
FORCEPROP 1 LAST LOCATION C963
J 2
(4209 542);
DISPLAY 0.723404 (4209 542);
PAINT GREEN (4209 542);
FORCEPROP 2 LAST $SEC 1
J 2
(4150 600);
DISPLAY 0.680851 (4150 600);
PAINT MONO (4150 600);
DISPLAY INVISIBLE (4150 600);
FORCEPROP 2 LAST CDS_SEC 1
J 2
(4150 600);
DISPLAY 0.680851 (4150 600);
DISPLAY INVISIBLE (4150 600);
FORCEPROP 2 LASTPIN (4050 525) $PN 1
J 0
(4060 535);
DISPLAY 0.808511 (4060 535);
FORCEPROP 2 LASTPIN (3900 525) $PN 2
J 2
(3890 535);
DISPLAY 0.808511 (3890 535);
FORCEPROP 2 LAST VALUE DIFF BUS_0.22UF
J 2
(3825 525);
DISPLAY 0.553191 (3825 525);
FORCEPROP 1 LAST PIN_NAMES_ROTATE TRUE
J 2
(3975 525);
DISPLAY 0.489362 (3975 525);
PAINT GREEN (3975 525);
DISPLAY INVISIBLE (3975 525);
FORCEPROP 2 LAST CDS_LIB pure_quanta
J 2
(3975 525);
DISPLAY INVISIBLE (3975 525);
FORCEPROP 1 LAST CDS_LMAN_SYM_OUTLINE -25,50,25,-50
J 2
(3975 525);
DISPLAY 0.468085 (3975 525);
PAINT GREEN (3975 525);
DISPLAY INVISIBLE (3975 525);
FORCEPROP 2 LAST VOLTAGE 6.3V
J 2
(3625 575);
DISPLAY 0.553191 (3625 575);
DISPLAY INVISIBLE (3625 575);
FORCEPROP 1 LAST MATERIAL X6S
J 2
(3984 604);
DISPLAY 0.574468 (3984 604);
PAINT GREEN (3984 604);
DISPLAY INVISIBLE (3984 604);
FORCEPROP 2 LAST PACK_TYPE C0201
J 2
(3800 575);
DISPLAY 0.553191 (3800 575);
DISPLAY INVISIBLE (3800 575);
FORCEPROP 2 LAST TOLERANCE 20%
J 2
(3900 575);
DISPLAY 0.553191 (3900 575);
DISPLAY INVISIBLE (3900 575);
FORCEPROP 1 LAST PART_NUMBER SP_CH4221MEE01
J 2
(3859 613);
DISPLAY 0.574468 (3859 613);
PAINT GREEN (3859 613);
DISPLAY INVISIBLE (3859 613);
FORCEPROP 1 LAST LOCATION C963
J 0
(4225 600);
DISPLAY 1.021277 (4225 600);
DISPLAY INVISIBLE (4225 600);
FORCEPROP 1 LAST PATH I123
J 2
(3975 525);
DISPLAY 0.723404 (3975 525);
DISPLAY INVISIBLE (3975 525);
FORCEADD Q_CAP_DIFFBUS..2
R 2
(3975 575);
FORCEPROP 1 LAST LOCATION C962
J 2
(4209 592);
DISPLAY 0.723404 (4209 592);
PAINT GREEN (4209 592);
FORCEPROP 2 LAST $SEC 1
J 2
(4150 650);
DISPLAY 0.680851 (4150 650);
PAINT MONO (4150 650);
DISPLAY INVISIBLE (4150 650);
FORCEPROP 2 LAST CDS_SEC 1
J 2
(4150 650);
DISPLAY 0.680851 (4150 650);
DISPLAY INVISIBLE (4150 650);
FORCEPROP 2 LASTPIN (4050 575) $PN 1
J 0
(4060 585);
DISPLAY 0.808511 (4060 585);
FORCEPROP 2 LASTPIN (3900 575) $PN 2
J 2
(3890 585);
DISPLAY 0.808511 (3890 585);
FORCEPROP 2 LAST VALUE DIFF BUS_0.22UF
J 2
(3825 575);
DISPLAY 0.553191 (3825 575);
FORCEPROP 1 LAST PIN_NAMES_ROTATE TRUE
J 2
(3975 575);
DISPLAY 0.489362 (3975 575);
PAINT GREEN (3975 575);
DISPLAY INVISIBLE (3975 575);
FORCEPROP 1 LAST CDS_LMAN_SYM_OUTLINE -25,50,25,-50
J 2
(3975 575);
DISPLAY 0.468085 (3975 575);
PAINT GREEN (3975 575);
DISPLAY INVISIBLE (3975 575);
FORCEPROP 2 LAST CDS_LIB pure_quanta
J 2
(3975 575);
DISPLAY INVISIBLE (3975 575);
FORCEPROP 2 LAST VOLTAGE 6.3V
J 2
(3625 625);
DISPLAY 0.553191 (3625 625);
DISPLAY INVISIBLE (3625 625);
FORCEPROP 1 LAST MATERIAL X6S
J 2
(3984 654);
DISPLAY 0.574468 (3984 654);
PAINT GREEN (3984 654);
DISPLAY INVISIBLE (3984 654);
FORCEPROP 2 LAST PACK_TYPE C0201
J 2
(3800 625);
DISPLAY 0.553191 (3800 625);
DISPLAY INVISIBLE (3800 625);
FORCEPROP 2 LAST TOLERANCE 20%
J 2
(3900 625);
DISPLAY 0.553191 (3900 625);
DISPLAY INVISIBLE (3900 625);
FORCEPROP 1 LAST PART_NUMBER SP_CH4221MEE01
J 2
(3859 663);
DISPLAY 0.574468 (3859 663);
PAINT GREEN (3859 663);
DISPLAY INVISIBLE (3859 663);
FORCEPROP 1 LAST LOCATION C962
J 0
(4225 650);
DISPLAY 1.021277 (4225 650);
DISPLAY INVISIBLE (4225 650);
FORCEPROP 1 LAST PATH I124
J 2
(3975 575);
DISPLAY 0.723404 (3975 575);
DISPLAY INVISIBLE (3975 575);
FORCEADD Q_CAP_DIFFBUS..2
R 2
(3975 725);
FORCEPROP 1 LAST LOCATION C961
J 2
(4209 742);
DISPLAY 0.723404 (4209 742);
PAINT GREEN (4209 742);
FORCEPROP 2 LAST $SEC 1
J 2
(4150 800);
DISPLAY 0.680851 (4150 800);
PAINT MONO (4150 800);
DISPLAY INVISIBLE (4150 800);
FORCEPROP 2 LAST CDS_SEC 1
J 2
(4150 800);
DISPLAY 0.680851 (4150 800);
DISPLAY INVISIBLE (4150 800);
FORCEPROP 2 LASTPIN (4050 725) $PN 1
J 0
(4060 735);
DISPLAY 0.808511 (4060 735);
FORCEPROP 2 LASTPIN (3900 725) $PN 2
J 2
(3890 735);
DISPLAY 0.808511 (3890 735);
FORCEPROP 2 LAST VALUE DIFF BUS_0.22UF
J 2
(3825 725);
DISPLAY 0.553191 (3825 725);
FORCEPROP 1 LAST PIN_NAMES_ROTATE TRUE
J 2
(3975 725);
DISPLAY 0.489362 (3975 725);
PAINT GREEN (3975 725);
DISPLAY INVISIBLE (3975 725);
FORCEPROP 2 LAST CDS_LIB pure_quanta
J 2
(3975 725);
DISPLAY INVISIBLE (3975 725);
FORCEPROP 1 LAST CDS_LMAN_SYM_OUTLINE -25,50,25,-50
J 2
(3975 725);
DISPLAY 0.468085 (3975 725);
PAINT GREEN (3975 725);
DISPLAY INVISIBLE (3975 725);
FORCEPROP 2 LAST VOLTAGE 6.3V
J 2
(3625 775);
DISPLAY 0.553191 (3625 775);
DISPLAY INVISIBLE (3625 775);
FORCEPROP 1 LAST MATERIAL X6S
J 2
(3984 804);
DISPLAY 0.574468 (3984 804);
PAINT GREEN (3984 804);
DISPLAY INVISIBLE (3984 804);
FORCEPROP 2 LAST PACK_TYPE C0201
J 2
(3800 775);
DISPLAY 0.553191 (3800 775);
DISPLAY INVISIBLE (3800 775);
FORCEPROP 2 LAST TOLERANCE 20%
J 2
(3900 775);
DISPLAY 0.553191 (3900 775);
DISPLAY INVISIBLE (3900 775);
FORCEPROP 1 LAST PART_NUMBER SP_CH4221MEE01
J 2
(3859 813);
DISPLAY 0.574468 (3859 813);
PAINT GREEN (3859 813);
DISPLAY INVISIBLE (3859 813);
FORCEPROP 1 LAST LOCATION C961
J 0
(4225 800);
DISPLAY 1.021277 (4225 800);
DISPLAY INVISIBLE (4225 800);
FORCEPROP 1 LAST PATH I125
J 2
(3975 725);
DISPLAY 0.723404 (3975 725);
DISPLAY INVISIBLE (3975 725);
FORCEADD Q_CAP_DIFFBUS..2
R 2
(3975 775);
FORCEPROP 1 LAST LOCATION C960
J 2
(4209 792);
DISPLAY 0.723404 (4209 792);
PAINT GREEN (4209 792);
FORCEPROP 2 LAST $SEC 1
J 2
(4150 850);
DISPLAY 0.680851 (4150 850);
PAINT MONO (4150 850);
DISPLAY INVISIBLE (4150 850);
FORCEPROP 2 LAST CDS_SEC 1
J 2
(4150 850);
DISPLAY 0.680851 (4150 850);
DISPLAY INVISIBLE (4150 850);
FORCEPROP 2 LASTPIN (4050 775) $PN 1
J 0
(4060 785);
DISPLAY 0.808511 (4060 785);
FORCEPROP 2 LASTPIN (3900 775) $PN 2
J 2
(3890 785);
DISPLAY 0.808511 (3890 785);
FORCEPROP 2 LAST VALUE DIFF BUS_0.22UF
J 2
(3825 775);
DISPLAY 0.553191 (3825 775);
FORCEPROP 1 LAST PIN_NAMES_ROTATE TRUE
J 2
(3975 775);
DISPLAY 0.489362 (3975 775);
PAINT GREEN (3975 775);
DISPLAY INVISIBLE (3975 775);
FORCEPROP 2 LAST CDS_LIB pure_quanta
J 2
(3975 775);
DISPLAY INVISIBLE (3975 775);
FORCEPROP 1 LAST CDS_LMAN_SYM_OUTLINE -25,50,25,-50
J 2
(3975 775);
DISPLAY 0.468085 (3975 775);
PAINT GREEN (3975 775);
DISPLAY INVISIBLE (3975 775);
FORCEPROP 2 LAST VOLTAGE 6.3V
J 2
(3625 825);
DISPLAY 0.553191 (3625 825);
DISPLAY INVISIBLE (3625 825);
FORCEPROP 1 LAST MATERIAL X6S
J 2
(3984 854);
DISPLAY 0.574468 (3984 854);
PAINT GREEN (3984 854);
DISPLAY INVISIBLE (3984 854);
FORCEPROP 2 LAST PACK_TYPE C0201
J 2
(3800 825);
DISPLAY 0.553191 (3800 825);
DISPLAY INVISIBLE (3800 825);
FORCEPROP 2 LAST TOLERANCE 20%
J 2
(3900 825);
DISPLAY 0.553191 (3900 825);
DISPLAY INVISIBLE (3900 825);
FORCEPROP 1 LAST PART_NUMBER SP_CH4221MEE01
J 2
(3859 863);
DISPLAY 0.574468 (3859 863);
PAINT GREEN (3859 863);
DISPLAY INVISIBLE (3859 863);
FORCEPROP 1 LAST LOCATION C960
J 0
(4225 850);
DISPLAY 1.021277 (4225 850);
DISPLAY INVISIBLE (4225 850);
FORCEPROP 1 LAST PATH I126
J 2
(3975 775);
DISPLAY 0.723404 (3975 775);
DISPLAY INVISIBLE (3975 775);
FORCEADD Q_CAP_DIFFBUS..2
R 2
(3975 925);
FORCEPROP 1 LAST LOCATION C959
J 2
(4209 942);
DISPLAY 0.723404 (4209 942);
PAINT GREEN (4209 942);
FORCEPROP 2 LAST $SEC 1
J 2
(4150 1000);
DISPLAY 0.680851 (4150 1000);
PAINT MONO (4150 1000);
DISPLAY INVISIBLE (4150 1000);
FORCEPROP 2 LAST CDS_SEC 1
J 2
(4150 1000);
DISPLAY 0.680851 (4150 1000);
DISPLAY INVISIBLE (4150 1000);
FORCEPROP 2 LASTPIN (4050 925) $PN 1
J 0
(4060 935);
DISPLAY 0.808511 (4060 935);
FORCEPROP 2 LASTPIN (3900 925) $PN 2
J 2
(3890 935);
DISPLAY 0.808511 (3890 935);
FORCEPROP 2 LAST VALUE DIFF BUS_0.22UF
J 2
(3825 925);
DISPLAY 0.553191 (3825 925);
FORCEPROP 1 LAST PIN_NAMES_ROTATE TRUE
J 2
(3975 925);
DISPLAY 0.489362 (3975 925);
PAINT GREEN (3975 925);
DISPLAY INVISIBLE (3975 925);
FORCEPROP 1 LAST CDS_LMAN_SYM_OUTLINE -25,50,25,-50
J 2
(3975 925);
DISPLAY 0.468085 (3975 925);
PAINT GREEN (3975 925);
DISPLAY INVISIBLE (3975 925);
FORCEPROP 2 LAST CDS_LIB pure_quanta
J 2
(3975 925);
DISPLAY INVISIBLE (3975 925);
FORCEPROP 2 LAST VOLTAGE 6.3V
J 2
(3625 975);
DISPLAY 0.553191 (3625 975);
DISPLAY INVISIBLE (3625 975);
FORCEPROP 1 LAST MATERIAL X6S
J 2
(3984 1004);
DISPLAY 0.574468 (3984 1004);
PAINT GREEN (3984 1004);
DISPLAY INVISIBLE (3984 1004);
FORCEPROP 2 LAST PACK_TYPE C0201
J 2
(3800 975);
DISPLAY 0.553191 (3800 975);
DISPLAY INVISIBLE (3800 975);
FORCEPROP 2 LAST TOLERANCE 20%
J 2
(3900 975);
DISPLAY 0.553191 (3900 975);
DISPLAY INVISIBLE (3900 975);
FORCEPROP 1 LAST PART_NUMBER SP_CH4221MEE01
J 2
(3859 1013);
DISPLAY 0.574468 (3859 1013);
PAINT GREEN (3859 1013);
DISPLAY INVISIBLE (3859 1013);
FORCEPROP 1 LAST LOCATION C959
J 0
(4225 1000);
DISPLAY 1.021277 (4225 1000);
DISPLAY INVISIBLE (4225 1000);
FORCEPROP 1 LAST PATH I127
J 2
(3975 925);
DISPLAY 0.723404 (3975 925);
DISPLAY INVISIBLE (3975 925);
FORCEADD Q_CAP_DIFFBUS..2
R 2
(3975 975);
FORCEPROP 1 LAST LOCATION C958
J 2
(4209 992);
DISPLAY 0.723404 (4209 992);
PAINT GREEN (4209 992);
FORCEPROP 2 LAST $SEC 1
J 2
(4150 1050);
DISPLAY 0.680851 (4150 1050);
PAINT MONO (4150 1050);
DISPLAY INVISIBLE (4150 1050);
FORCEPROP 2 LAST CDS_SEC 1
J 2
(4150 1050);
DISPLAY 0.680851 (4150 1050);
DISPLAY INVISIBLE (4150 1050);
FORCEPROP 2 LASTPIN (4050 975) $PN 1
J 0
(4060 985);
DISPLAY 0.808511 (4060 985);
FORCEPROP 2 LASTPIN (3900 975) $PN 2
J 2
(3890 985);
DISPLAY 0.808511 (3890 985);
FORCEPROP 2 LAST VALUE DIFF BUS_0.22UF
J 2
(3825 975);
DISPLAY 0.553191 (3825 975);
FORCEPROP 1 LAST PIN_NAMES_ROTATE TRUE
J 2
(3975 975);
DISPLAY 0.489362 (3975 975);
PAINT GREEN (3975 975);
DISPLAY INVISIBLE (3975 975);
FORCEPROP 1 LAST CDS_LMAN_SYM_OUTLINE -25,50,25,-50
J 2
(3975 975);
DISPLAY 0.468085 (3975 975);
PAINT GREEN (3975 975);
DISPLAY INVISIBLE (3975 975);
FORCEPROP 2 LAST CDS_LIB pure_quanta
J 2
(3975 975);
DISPLAY INVISIBLE (3975 975);
FORCEPROP 2 LAST VOLTAGE 6.3V
J 2
(3625 1025);
DISPLAY 0.553191 (3625 1025);
DISPLAY INVISIBLE (3625 1025);
FORCEPROP 1 LAST MATERIAL X6S
J 2
(3984 1054);
DISPLAY 0.574468 (3984 1054);
PAINT GREEN (3984 1054);
DISPLAY INVISIBLE (3984 1054);
FORCEPROP 2 LAST PACK_TYPE C0201
J 2
(3800 1025);
DISPLAY 0.553191 (3800 1025);
DISPLAY INVISIBLE (3800 1025);
FORCEPROP 2 LAST TOLERANCE 20%
J 2
(3900 1025);
DISPLAY 0.553191 (3900 1025);
DISPLAY INVISIBLE (3900 1025);
FORCEPROP 1 LAST PART_NUMBER SP_CH4221MEE01
J 2
(3859 1063);
DISPLAY 0.574468 (3859 1063);
PAINT GREEN (3859 1063);
DISPLAY INVISIBLE (3859 1063);
FORCEPROP 1 LAST LOCATION C958
J 0
(4225 1050);
DISPLAY 1.021277 (4225 1050);
DISPLAY INVISIBLE (4225 1050);
FORCEPROP 1 LAST PATH I128
J 2
(3975 975);
DISPLAY 0.723404 (3975 975);
DISPLAY INVISIBLE (3975 975);
FORCEADD TAP..1
R 2
(3250 1375);
FORCEPROP 3 LASTPIN (3300 1375) SIG_NAME P5E_CPU0_P1_TX_DN<5>
J 0
(3310 1385);
DISPLAY 0.659574 (3310 1385);
PAINT MONO (3310 1385);
DISPLAY INVISIBLE (3310 1385);
FORCEPROP 1 LASTPIN (3300 1375) BN 5
J 2
(3312 1383);
DISPLAY 0.680851 (3312 1383);
PAINT GREEN (3312 1383);
FORCEPROP 2 LAST CDS_LIB standard
J 0
(3250 1375);
DISPLAY INVISIBLE (3250 1375);
FORCEPROP 1 LAST BODY_TYPE PLUMBING
J 2
(3250 1425);
DISPLAY 0.872340 (3250 1425);
PAINT GREEN (3250 1425);
DISPLAY INVISIBLE (3250 1425);
FORCEPROP 1 LAST HDL_TAP TRUE
J 2
(2925 1250);
DISPLAY 0.872340 (2925 1250);
DISPLAY INVISIBLE (2925 1250);
FORCEPROP 1 LAST PATH I129
J 2
(3252 1375);
DISPLAY 0.872340 (3252 1375);
PAINT GREEN (3252 1375);
DISPLAY INVISIBLE (3252 1375);
FORCEADD TAP..1
R 2
(-1300 975);
FORCEPROP 3 LASTPIN (-1250 975) SIG_NAME P5E_CPU0_P0_TX_DN<3>
J 0
(-1240 985);
DISPLAY 0.659574 (-1240 985);
PAINT MONO (-1240 985);
DISPLAY INVISIBLE (-1240 985);
FORCEPROP 1 LASTPIN (-1250 975) BN 3
J 2
(-1238 983);
DISPLAY 0.680851 (-1238 983);
PAINT GREEN (-1238 983);
FORCEPROP 2 LAST CDS_LIB standard
J 0
(-1300 975);
DISPLAY INVISIBLE (-1300 975);
FORCEPROP 1 LAST BODY_TYPE PLUMBING
J 2
(-1300 1025);
DISPLAY 0.872340 (-1300 1025);
PAINT GREEN (-1300 1025);
DISPLAY INVISIBLE (-1300 1025);
FORCEPROP 1 LAST HDL_TAP TRUE
J 2
(-1625 850);
DISPLAY 0.872340 (-1625 850);
DISPLAY INVISIBLE (-1625 850);
FORCEPROP 1 LAST PATH I13
J 2
(-1298 975);
DISPLAY 0.872340 (-1298 975);
PAINT GREEN (-1298 975);
DISPLAY INVISIBLE (-1298 975);
FORCEADD TAP..1
R 2
(3250 1175);
FORCEPROP 3 LASTPIN (3300 1175) SIG_NAME P5E_CPU0_P1_TX_DN<4>
J 0
(3310 1185);
DISPLAY 0.659574 (3310 1185);
PAINT MONO (3310 1185);
DISPLAY INVISIBLE (3310 1185);
FORCEPROP 1 LASTPIN (3300 1175) BN 4
J 2
(3312 1183);
DISPLAY 0.680851 (3312 1183);
PAINT GREEN (3312 1183);
FORCEPROP 2 LAST CDS_LIB standard
J 0
(3250 1175);
DISPLAY INVISIBLE (3250 1175);
FORCEPROP 1 LAST BODY_TYPE PLUMBING
J 2
(3250 1225);
DISPLAY 0.872340 (3250 1225);
PAINT GREEN (3250 1225);
DISPLAY INVISIBLE (3250 1225);
FORCEPROP 1 LAST HDL_TAP TRUE
J 2
(2925 1050);
DISPLAY 0.872340 (2925 1050);
DISPLAY INVISIBLE (2925 1050);
FORCEPROP 1 LAST PATH I130
J 2
(3252 1175);
DISPLAY 0.872340 (3252 1175);
PAINT GREEN (3252 1175);
DISPLAY INVISIBLE (3252 1175);
FORCEADD TAP..1
R 2
(3250 1575);
FORCEPROP 3 LASTPIN (3300 1575) SIG_NAME P5E_CPU0_P1_TX_DN<6>
J 0
(3310 1585);
DISPLAY 0.659574 (3310 1585);
PAINT MONO (3310 1585);
DISPLAY INVISIBLE (3310 1585);
FORCEPROP 1 LASTPIN (3300 1575) BN 6
J 2
(3312 1583);
DISPLAY 0.680851 (3312 1583);
PAINT GREEN (3312 1583);
FORCEPROP 2 LAST CDS_LIB standard
J 0
(3250 1575);
DISPLAY INVISIBLE (3250 1575);
FORCEPROP 1 LAST BODY_TYPE PLUMBING
J 2
(3250 1625);
DISPLAY 0.872340 (3250 1625);
PAINT GREEN (3250 1625);
DISPLAY INVISIBLE (3250 1625);
FORCEPROP 1 LAST HDL_TAP TRUE
J 2
(2925 1450);
DISPLAY 0.872340 (2925 1450);
DISPLAY INVISIBLE (2925 1450);
FORCEPROP 1 LAST PATH I131
J 2
(3252 1575);
DISPLAY 0.872340 (3252 1575);
PAINT GREEN (3252 1575);
DISPLAY INVISIBLE (3252 1575);
FORCEADD TAP..1
R 2
(3250 1775);
FORCEPROP 3 LASTPIN (3300 1775) SIG_NAME P5E_CPU0_P1_TX_DN<7>
J 0
(3310 1785);
DISPLAY 0.659574 (3310 1785);
PAINT MONO (3310 1785);
DISPLAY INVISIBLE (3310 1785);
FORCEPROP 1 LASTPIN (3300 1775) BN 7
J 2
(3312 1783);
DISPLAY 0.680851 (3312 1783);
PAINT GREEN (3312 1783);
FORCEPROP 2 LAST CDS_LIB standard
J 0
(3250 1775);
DISPLAY INVISIBLE (3250 1775);
FORCEPROP 1 LAST BODY_TYPE PLUMBING
J 2
(3250 1825);
DISPLAY 0.872340 (3250 1825);
PAINT GREEN (3250 1825);
DISPLAY INVISIBLE (3250 1825);
FORCEPROP 1 LAST HDL_TAP TRUE
J 2
(2925 1650);
DISPLAY 0.872340 (2925 1650);
DISPLAY INVISIBLE (2925 1650);
FORCEPROP 1 LAST PATH I132
J 2
(3252 1775);
DISPLAY 0.872340 (3252 1775);
PAINT GREEN (3252 1775);
DISPLAY INVISIBLE (3252 1775);
FORCEADD Q_CAP_DIFFBUS..2
R 2
(3975 1375);
FORCEPROP 1 LAST LOCATION C954
J 2
(4209 1392);
DISPLAY 0.723404 (4209 1392);
PAINT GREEN (4209 1392);
FORCEPROP 2 LAST $SEC 1
J 2
(4150 1450);
DISPLAY 0.680851 (4150 1450);
PAINT MONO (4150 1450);
DISPLAY INVISIBLE (4150 1450);
FORCEPROP 2 LAST CDS_SEC 1
J 2
(4150 1450);
DISPLAY 0.680851 (4150 1450);
DISPLAY INVISIBLE (4150 1450);
FORCEPROP 2 LASTPIN (4050 1375) $PN 1
J 0
(4060 1385);
DISPLAY 0.808511 (4060 1385);
FORCEPROP 2 LASTPIN (3900 1375) $PN 2
J 2
(3890 1385);
DISPLAY 0.808511 (3890 1385);
FORCEPROP 2 LAST VALUE DIFF BUS_0.22UF
J 2
(3825 1375);
DISPLAY 0.553191 (3825 1375);
FORCEPROP 1 LAST PIN_NAMES_ROTATE TRUE
J 2
(3975 1375);
DISPLAY 0.489362 (3975 1375);
PAINT GREEN (3975 1375);
DISPLAY INVISIBLE (3975 1375);
FORCEPROP 2 LAST CDS_LIB pure_quanta
J 2
(3975 1375);
DISPLAY INVISIBLE (3975 1375);
FORCEPROP 1 LAST CDS_LMAN_SYM_OUTLINE -25,50,25,-50
J 2
(3975 1375);
DISPLAY 0.468085 (3975 1375);
PAINT GREEN (3975 1375);
DISPLAY INVISIBLE (3975 1375);
FORCEPROP 2 LAST VOLTAGE 6.3V
J 2
(3625 1425);
DISPLAY 0.553191 (3625 1425);
DISPLAY INVISIBLE (3625 1425);
FORCEPROP 1 LAST MATERIAL X6S
J 2
(3984 1454);
DISPLAY 0.574468 (3984 1454);
PAINT GREEN (3984 1454);
DISPLAY INVISIBLE (3984 1454);
FORCEPROP 2 LAST PACK_TYPE C0201
J 2
(3800 1425);
DISPLAY 0.553191 (3800 1425);
DISPLAY INVISIBLE (3800 1425);
FORCEPROP 2 LAST TOLERANCE 20%
J 2
(3900 1425);
DISPLAY 0.553191 (3900 1425);
DISPLAY INVISIBLE (3900 1425);
FORCEPROP 1 LAST PART_NUMBER SP_CH4221MEE01
J 2
(3859 1463);
DISPLAY 0.574468 (3859 1463);
PAINT GREEN (3859 1463);
DISPLAY INVISIBLE (3859 1463);
FORCEPROP 1 LAST LOCATION C954
J 0
(4225 1450);
DISPLAY 1.021277 (4225 1450);
DISPLAY INVISIBLE (4225 1450);
FORCEPROP 1 LAST PATH I133
J 2
(3975 1375);
DISPLAY 0.723404 (3975 1375);
DISPLAY INVISIBLE (3975 1375);
FORCEADD Q_CAP_DIFFBUS..2
R 2
(3975 1525);
FORCEPROP 1 LAST LOCATION C953
J 2
(4209 1542);
DISPLAY 0.723404 (4209 1542);
PAINT GREEN (4209 1542);
FORCEPROP 2 LAST $SEC 1
J 2
(4150 1600);
DISPLAY 0.680851 (4150 1600);
PAINT MONO (4150 1600);
DISPLAY INVISIBLE (4150 1600);
FORCEPROP 2 LAST CDS_SEC 1
J 2
(4150 1600);
DISPLAY 0.680851 (4150 1600);
DISPLAY INVISIBLE (4150 1600);
FORCEPROP 2 LASTPIN (4050 1525) $PN 1
J 0
(4060 1535);
DISPLAY 0.808511 (4060 1535);
FORCEPROP 2 LASTPIN (3900 1525) $PN 2
J 2
(3890 1535);
DISPLAY 0.808511 (3890 1535);
FORCEPROP 2 LAST VALUE DIFF BUS_0.22UF
J 2
(3825 1525);
DISPLAY 0.553191 (3825 1525);
FORCEPROP 1 LAST PIN_NAMES_ROTATE TRUE
J 2
(3975 1525);
DISPLAY 0.489362 (3975 1525);
PAINT GREEN (3975 1525);
DISPLAY INVISIBLE (3975 1525);
FORCEPROP 2 LAST CDS_LIB pure_quanta
J 2
(3975 1525);
DISPLAY INVISIBLE (3975 1525);
FORCEPROP 1 LAST CDS_LMAN_SYM_OUTLINE -25,50,25,-50
J 2
(3975 1525);
DISPLAY 0.468085 (3975 1525);
PAINT GREEN (3975 1525);
DISPLAY INVISIBLE (3975 1525);
FORCEPROP 2 LAST VOLTAGE 6.3V
J 2
(3625 1575);
DISPLAY 0.553191 (3625 1575);
DISPLAY INVISIBLE (3625 1575);
FORCEPROP 1 LAST MATERIAL X6S
J 2
(3984 1604);
DISPLAY 0.574468 (3984 1604);
PAINT GREEN (3984 1604);
DISPLAY INVISIBLE (3984 1604);
FORCEPROP 2 LAST PACK_TYPE C0201
J 2
(3800 1575);
DISPLAY 0.553191 (3800 1575);
DISPLAY INVISIBLE (3800 1575);
FORCEPROP 2 LAST TOLERANCE 20%
J 2
(3900 1575);
DISPLAY 0.553191 (3900 1575);
DISPLAY INVISIBLE (3900 1575);
FORCEPROP 1 LAST PART_NUMBER SP_CH4221MEE01
J 2
(3859 1613);
DISPLAY 0.574468 (3859 1613);
PAINT GREEN (3859 1613);
DISPLAY INVISIBLE (3859 1613);
FORCEPROP 1 LAST LOCATION C953
J 0
(4225 1600);
DISPLAY 1.021277 (4225 1600);
DISPLAY INVISIBLE (4225 1600);
FORCEPROP 1 LAST PATH I134
J 2
(3975 1525);
DISPLAY 0.723404 (3975 1525);
DISPLAY INVISIBLE (3975 1525);
FORCEADD Q_CAP_DIFFBUS..2
R 2
(3975 1575);
FORCEPROP 1 LAST LOCATION C952
J 2
(4209 1592);
DISPLAY 0.723404 (4209 1592);
PAINT GREEN (4209 1592);
FORCEPROP 2 LAST $SEC 1
J 2
(4150 1650);
DISPLAY 0.680851 (4150 1650);
PAINT MONO (4150 1650);
DISPLAY INVISIBLE (4150 1650);
FORCEPROP 2 LAST CDS_SEC 1
J 2
(4150 1650);
DISPLAY 0.680851 (4150 1650);
DISPLAY INVISIBLE (4150 1650);
FORCEPROP 2 LASTPIN (4050 1575) $PN 1
J 0
(4060 1585);
DISPLAY 0.808511 (4060 1585);
FORCEPROP 2 LASTPIN (3900 1575) $PN 2
J 2
(3890 1585);
DISPLAY 0.808511 (3890 1585);
FORCEPROP 2 LAST VALUE DIFF BUS_0.22UF
J 2
(3825 1575);
DISPLAY 0.553191 (3825 1575);
FORCEPROP 1 LAST PIN_NAMES_ROTATE TRUE
J 2
(3975 1575);
DISPLAY 0.489362 (3975 1575);
PAINT GREEN (3975 1575);
DISPLAY INVISIBLE (3975 1575);
FORCEPROP 2 LAST CDS_LIB pure_quanta
J 2
(3975 1575);
DISPLAY INVISIBLE (3975 1575);
FORCEPROP 1 LAST CDS_LMAN_SYM_OUTLINE -25,50,25,-50
J 2
(3975 1575);
DISPLAY 0.468085 (3975 1575);
PAINT GREEN (3975 1575);
DISPLAY INVISIBLE (3975 1575);
FORCEPROP 2 LAST VOLTAGE 6.3V
J 2
(3625 1625);
DISPLAY 0.553191 (3625 1625);
DISPLAY INVISIBLE (3625 1625);
FORCEPROP 1 LAST MATERIAL X6S
J 2
(3984 1654);
DISPLAY 0.574468 (3984 1654);
PAINT GREEN (3984 1654);
DISPLAY INVISIBLE (3984 1654);
FORCEPROP 2 LAST PACK_TYPE C0201
J 2
(3800 1625);
DISPLAY 0.553191 (3800 1625);
DISPLAY INVISIBLE (3800 1625);
FORCEPROP 2 LAST TOLERANCE 20%
J 2
(3900 1625);
DISPLAY 0.553191 (3900 1625);
DISPLAY INVISIBLE (3900 1625);
FORCEPROP 1 LAST PART_NUMBER SP_CH4221MEE01
J 2
(3859 1663);
DISPLAY 0.574468 (3859 1663);
PAINT GREEN (3859 1663);
DISPLAY INVISIBLE (3859 1663);
FORCEPROP 1 LAST LOCATION C952
J 0
(4225 1650);
DISPLAY 1.021277 (4225 1650);
DISPLAY INVISIBLE (4225 1650);
FORCEPROP 1 LAST PATH I135
J 2
(3975 1575);
DISPLAY 0.723404 (3975 1575);
DISPLAY INVISIBLE (3975 1575);
FORCEADD Q_CAP_DIFFBUS..2
R 2
(3975 1725);
FORCEPROP 1 LAST LOCATION C951
J 2
(4209 1742);
DISPLAY 0.723404 (4209 1742);
PAINT GREEN (4209 1742);
FORCEPROP 2 LAST $SEC 1
J 2
(4150 1800);
DISPLAY 0.680851 (4150 1800);
PAINT MONO (4150 1800);
DISPLAY INVISIBLE (4150 1800);
FORCEPROP 2 LAST CDS_SEC 1
J 2
(4150 1800);
DISPLAY 0.680851 (4150 1800);
DISPLAY INVISIBLE (4150 1800);
FORCEPROP 2 LASTPIN (4050 1725) $PN 1
J 0
(4060 1735);
DISPLAY 0.808511 (4060 1735);
FORCEPROP 2 LASTPIN (3900 1725) $PN 2
J 2
(3890 1735);
DISPLAY 0.808511 (3890 1735);
FORCEPROP 2 LAST VALUE DIFF BUS_0.22UF
J 2
(3825 1725);
DISPLAY 0.553191 (3825 1725);
FORCEPROP 1 LAST PIN_NAMES_ROTATE TRUE
J 2
(3975 1725);
DISPLAY 0.489362 (3975 1725);
PAINT GREEN (3975 1725);
DISPLAY INVISIBLE (3975 1725);
FORCEPROP 2 LAST CDS_LIB pure_quanta
J 2
(3975 1725);
DISPLAY INVISIBLE (3975 1725);
FORCEPROP 1 LAST CDS_LMAN_SYM_OUTLINE -25,50,25,-50
J 2
(3975 1725);
DISPLAY 0.468085 (3975 1725);
PAINT GREEN (3975 1725);
DISPLAY INVISIBLE (3975 1725);
FORCEPROP 2 LAST VOLTAGE 6.3V
J 2
(3625 1775);
DISPLAY 0.553191 (3625 1775);
DISPLAY INVISIBLE (3625 1775);
FORCEPROP 1 LAST MATERIAL X6S
J 2
(3984 1804);
DISPLAY 0.574468 (3984 1804);
PAINT GREEN (3984 1804);
DISPLAY INVISIBLE (3984 1804);
FORCEPROP 2 LAST PACK_TYPE C0201
J 2
(3800 1775);
DISPLAY 0.553191 (3800 1775);
DISPLAY INVISIBLE (3800 1775);
FORCEPROP 2 LAST TOLERANCE 20%
J 2
(3900 1775);
DISPLAY 0.553191 (3900 1775);
DISPLAY INVISIBLE (3900 1775);
FORCEPROP 1 LAST PART_NUMBER SP_CH4221MEE01
J 2
(3859 1813);
DISPLAY 0.574468 (3859 1813);
PAINT GREEN (3859 1813);
DISPLAY INVISIBLE (3859 1813);
FORCEPROP 1 LAST LOCATION C951
J 0
(4225 1800);
DISPLAY 1.021277 (4225 1800);
DISPLAY INVISIBLE (4225 1800);
FORCEPROP 1 LAST PATH I136
J 2
(3975 1725);
DISPLAY 0.723404 (3975 1725);
DISPLAY INVISIBLE (3975 1725);
FORCEADD Q_CAP_DIFFBUS..2
R 2
(3975 1775);
FORCEPROP 1 LAST LOCATION C950
J 2
(4209 1792);
DISPLAY 0.723404 (4209 1792);
PAINT GREEN (4209 1792);
FORCEPROP 2 LAST $SEC 1
J 2
(4150 1850);
DISPLAY 0.680851 (4150 1850);
PAINT MONO (4150 1850);
DISPLAY INVISIBLE (4150 1850);
FORCEPROP 2 LAST CDS_SEC 1
J 2
(4150 1850);
DISPLAY 0.680851 (4150 1850);
DISPLAY INVISIBLE (4150 1850);
FORCEPROP 2 LASTPIN (4050 1775) $PN 1
J 0
(4060 1785);
DISPLAY 0.808511 (4060 1785);
FORCEPROP 2 LASTPIN (3900 1775) $PN 2
J 2
(3890 1785);
DISPLAY 0.808511 (3890 1785);
FORCEPROP 2 LAST VALUE DIFF BUS_0.22UF
J 2
(3825 1775);
DISPLAY 0.553191 (3825 1775);
FORCEPROP 1 LAST PIN_NAMES_ROTATE TRUE
J 2
(3975 1775);
DISPLAY 0.489362 (3975 1775);
PAINT GREEN (3975 1775);
DISPLAY INVISIBLE (3975 1775);
FORCEPROP 1 LAST CDS_LMAN_SYM_OUTLINE -25,50,25,-50
J 2
(3975 1775);
DISPLAY 0.468085 (3975 1775);
PAINT GREEN (3975 1775);
DISPLAY INVISIBLE (3975 1775);
FORCEPROP 2 LAST CDS_LIB pure_quanta
J 2
(3975 1775);
DISPLAY INVISIBLE (3975 1775);
FORCEPROP 2 LAST VOLTAGE 6.3V
J 2
(3625 1825);
DISPLAY 0.553191 (3625 1825);
DISPLAY INVISIBLE (3625 1825);
FORCEPROP 1 LAST MATERIAL X6S
J 2
(3984 1854);
DISPLAY 0.574468 (3984 1854);
PAINT GREEN (3984 1854);
DISPLAY INVISIBLE (3984 1854);
FORCEPROP 2 LAST PACK_TYPE C0201
J 2
(3800 1825);
DISPLAY 0.553191 (3800 1825);
DISPLAY INVISIBLE (3800 1825);
FORCEPROP 2 LAST TOLERANCE 20%
J 2
(3900 1825);
DISPLAY 0.553191 (3900 1825);
DISPLAY INVISIBLE (3900 1825);
FORCEPROP 1 LAST PART_NUMBER SP_CH4221MEE01
J 2
(3859 1863);
DISPLAY 0.574468 (3859 1863);
PAINT GREEN (3859 1863);
DISPLAY INVISIBLE (3859 1863);
FORCEPROP 1 LAST LOCATION C950
J 0
(4225 1850);
DISPLAY 1.021277 (4225 1850);
DISPLAY INVISIBLE (4225 1850);
FORCEPROP 1 LAST PATH I137
J 2
(3975 1775);
DISPLAY 0.723404 (3975 1775);
DISPLAY INVISIBLE (3975 1775);
FORCEADD TAP..1
R 2
(3000 2500);
FORCEPROP 3 LASTPIN (3050 2500) SIG_NAME P5E_CPU0_P1_TX_DP<9>
J 0
(3060 2510);
DISPLAY 0.659574 (3060 2510);
PAINT MONO (3060 2510);
DISPLAY INVISIBLE (3060 2510);
FORCEPROP 1 LASTPIN (3050 2500) BN 9
J 2
(3062 2508);
DISPLAY 0.680851 (3062 2508);
PAINT GREEN (3062 2508);
FORCEPROP 2 LAST CDS_LIB standard
J 0
(3000 2500);
DISPLAY INVISIBLE (3000 2500);
FORCEPROP 1 LAST BODY_TYPE PLUMBING
J 2
(3000 2550);
DISPLAY 0.872340 (3000 2550);
PAINT GREEN (3000 2550);
DISPLAY INVISIBLE (3000 2550);
FORCEPROP 1 LAST HDL_TAP TRUE
J 2
(2675 2375);
DISPLAY 0.872340 (2675 2375);
DISPLAY INVISIBLE (2675 2375);
FORCEPROP 1 LAST PATH I138
J 2
(3002 2500);
DISPLAY 0.872340 (3002 2500);
PAINT GREEN (3002 2500);
DISPLAY INVISIBLE (3002 2500);
FORCEADD TAP..1
R 2
(3000 2300);
FORCEPROP 3 LASTPIN (3050 2300) SIG_NAME P5E_CPU0_P1_TX_DP<8>
J 0
(3060 2310);
DISPLAY 0.659574 (3060 2310);
PAINT MONO (3060 2310);
DISPLAY INVISIBLE (3060 2310);
FORCEPROP 1 LASTPIN (3050 2300) BN 8
J 2
(3062 2308);
DISPLAY 0.680851 (3062 2308);
PAINT GREEN (3062 2308);
FORCEPROP 2 LAST CDS_LIB standard
J 0
(3000 2300);
DISPLAY INVISIBLE (3000 2300);
FORCEPROP 1 LAST BODY_TYPE PLUMBING
J 2
(3000 2350);
DISPLAY 0.872340 (3000 2350);
PAINT GREEN (3000 2350);
DISPLAY INVISIBLE (3000 2350);
FORCEPROP 1 LAST HDL_TAP TRUE
J 2
(2675 2175);
DISPLAY 0.872340 (2675 2175);
DISPLAY INVISIBLE (2675 2175);
FORCEPROP 1 LAST PATH I139
J 2
(3002 2300);
DISPLAY 0.872340 (3002 2300);
PAINT GREEN (3002 2300);
DISPLAY INVISIBLE (3002 2300);
FORCEADD TAP..1
R 2
(-1550 1325);
FORCEPROP 3 LASTPIN (-1500 1325) SIG_NAME P5E_CPU0_P0_TX_DP<5>
J 0
(-1490 1335);
DISPLAY 0.659574 (-1490 1335);
PAINT MONO (-1490 1335);
DISPLAY INVISIBLE (-1490 1335);
FORCEPROP 1 LASTPIN (-1500 1325) BN 5
J 2
(-1488 1333);
DISPLAY 0.680851 (-1488 1333);
PAINT GREEN (-1488 1333);
FORCEPROP 2 LAST CDS_LIB standard
J 0
(-1550 1325);
DISPLAY INVISIBLE (-1550 1325);
FORCEPROP 1 LAST BODY_TYPE PLUMBING
J 2
(-1550 1375);
DISPLAY 0.872340 (-1550 1375);
PAINT GREEN (-1550 1375);
DISPLAY INVISIBLE (-1550 1375);
FORCEPROP 1 LAST HDL_TAP TRUE
J 2
(-1875 1200);
DISPLAY 0.872340 (-1875 1200);
DISPLAY INVISIBLE (-1875 1200);
FORCEPROP 1 LAST PATH I14
J 2
(-1548 1325);
DISPLAY 0.872340 (-1548 1325);
PAINT GREEN (-1548 1325);
DISPLAY INVISIBLE (-1548 1325);
FORCEADD TAP..1
R 2
(3000 3100);
FORCEPROP 3 LASTPIN (3050 3100) SIG_NAME P5E_CPU0_P1_TX_DP<12>
J 0
(3060 3110);
DISPLAY 0.659574 (3060 3110);
PAINT MONO (3060 3110);
DISPLAY INVISIBLE (3060 3110);
FORCEPROP 1 LASTPIN (3050 3100) BN 12
J 2
(3062 3108);
DISPLAY 0.680851 (3062 3108);
PAINT GREEN (3062 3108);
FORCEPROP 2 LAST CDS_LIB standard
J 0
(3000 3100);
DISPLAY INVISIBLE (3000 3100);
FORCEPROP 1 LAST BODY_TYPE PLUMBING
J 2
(3000 3150);
DISPLAY 0.872340 (3000 3150);
PAINT GREEN (3000 3150);
DISPLAY INVISIBLE (3000 3150);
FORCEPROP 1 LAST HDL_TAP TRUE
J 2
(2675 2975);
DISPLAY 0.872340 (2675 2975);
DISPLAY INVISIBLE (2675 2975);
FORCEPROP 1 LAST PATH I140
J 2
(3002 3100);
DISPLAY 0.872340 (3002 3100);
PAINT GREEN (3002 3100);
DISPLAY INVISIBLE (3002 3100);
FORCEADD TAP..1
R 2
(3000 2900);
FORCEPROP 3 LASTPIN (3050 2900) SIG_NAME P5E_CPU0_P1_TX_DP<11>
J 0
(3060 2910);
DISPLAY 0.659574 (3060 2910);
PAINT MONO (3060 2910);
DISPLAY INVISIBLE (3060 2910);
FORCEPROP 1 LASTPIN (3050 2900) BN 11
J 2
(3062 2908);
DISPLAY 0.680851 (3062 2908);
PAINT GREEN (3062 2908);
FORCEPROP 2 LAST CDS_LIB standard
J 0
(3000 2900);
DISPLAY INVISIBLE (3000 2900);
FORCEPROP 1 LAST BODY_TYPE PLUMBING
J 2
(3000 2950);
DISPLAY 0.872340 (3000 2950);
PAINT GREEN (3000 2950);
DISPLAY INVISIBLE (3000 2950);
FORCEPROP 1 LAST HDL_TAP TRUE
J 2
(2675 2775);
DISPLAY 0.872340 (2675 2775);
DISPLAY INVISIBLE (2675 2775);
FORCEPROP 1 LAST PATH I141
J 2
(3002 2900);
DISPLAY 0.872340 (3002 2900);
PAINT GREEN (3002 2900);
DISPLAY INVISIBLE (3002 2900);
FORCEADD TAP..1
R 2
(3000 2700);
FORCEPROP 3 LASTPIN (3050 2700) SIG_NAME P5E_CPU0_P1_TX_DP<10>
J 0
(3060 2710);
DISPLAY 0.659574 (3060 2710);
PAINT MONO (3060 2710);
DISPLAY INVISIBLE (3060 2710);
FORCEPROP 1 LASTPIN (3050 2700) BN 10
J 2
(3062 2708);
DISPLAY 0.680851 (3062 2708);
PAINT GREEN (3062 2708);
FORCEPROP 2 LAST CDS_LIB standard
J 0
(3000 2700);
DISPLAY INVISIBLE (3000 2700);
FORCEPROP 1 LAST BODY_TYPE PLUMBING
J 2
(3000 2750);
DISPLAY 0.872340 (3000 2750);
PAINT GREEN (3000 2750);
DISPLAY INVISIBLE (3000 2750);
FORCEPROP 1 LAST HDL_TAP TRUE
J 2
(2675 2575);
DISPLAY 0.872340 (2675 2575);
DISPLAY INVISIBLE (2675 2575);
FORCEPROP 1 LAST PATH I142
J 2
(3002 2700);
DISPLAY 0.872340 (3002 2700);
PAINT GREEN (3002 2700);
DISPLAY INVISIBLE (3002 2700);
FORCEADD TAP..1
R 2
(3000 3300);
FORCEPROP 3 LASTPIN (3050 3300) SIG_NAME P5E_CPU0_P1_TX_DP<13>
J 0
(3060 3310);
DISPLAY 0.659574 (3060 3310);
PAINT MONO (3060 3310);
DISPLAY INVISIBLE (3060 3310);
FORCEPROP 1 LASTPIN (3050 3300) BN 13
J 2
(3062 3308);
DISPLAY 0.680851 (3062 3308);
PAINT GREEN (3062 3308);
FORCEPROP 2 LAST CDS_LIB standard
J 0
(3000 3300);
DISPLAY INVISIBLE (3000 3300);
FORCEPROP 1 LAST BODY_TYPE PLUMBING
J 2
(3000 3350);
DISPLAY 0.872340 (3000 3350);
PAINT GREEN (3000 3350);
DISPLAY INVISIBLE (3000 3350);
FORCEPROP 1 LAST HDL_TAP TRUE
J 2
(2675 3175);
DISPLAY 0.872340 (2675 3175);
DISPLAY INVISIBLE (2675 3175);
FORCEPROP 1 LAST PATH I143
J 2
(3002 3300);
DISPLAY 0.872340 (3002 3300);
PAINT GREEN (3002 3300);
DISPLAY INVISIBLE (3002 3300);
FORCEADD TAP..1
R 2
(3000 3500);
FORCEPROP 3 LASTPIN (3050 3500) SIG_NAME P5E_CPU0_P1_TX_DP<14>
J 0
(3060 3510);
DISPLAY 0.659574 (3060 3510);
PAINT MONO (3060 3510);
DISPLAY INVISIBLE (3060 3510);
FORCEPROP 1 LASTPIN (3050 3500) BN 14
J 2
(3062 3508);
DISPLAY 0.680851 (3062 3508);
PAINT GREEN (3062 3508);
FORCEPROP 2 LAST CDS_LIB standard
J 0
(3000 3500);
DISPLAY INVISIBLE (3000 3500);
FORCEPROP 1 LAST BODY_TYPE PLUMBING
J 2
(3000 3550);
DISPLAY 0.872340 (3000 3550);
PAINT GREEN (3000 3550);
DISPLAY INVISIBLE (3000 3550);
FORCEPROP 1 LAST HDL_TAP TRUE
J 2
(2675 3375);
DISPLAY 0.872340 (2675 3375);
DISPLAY INVISIBLE (2675 3375);
FORCEPROP 1 LAST PATH I144
J 2
(3002 3500);
DISPLAY 0.872340 (3002 3500);
PAINT GREEN (3002 3500);
DISPLAY INVISIBLE (3002 3500);
FORCEADD TAP..1
R 2
(3000 3700);
FORCEPROP 3 LASTPIN (3050 3700) SIG_NAME P5E_CPU0_P1_TX_DP<15>
J 0
(3060 3710);
DISPLAY 0.659574 (3060 3710);
PAINT MONO (3060 3710);
DISPLAY INVISIBLE (3060 3710);
FORCEPROP 1 LASTPIN (3050 3700) BN 15
J 2
(3062 3708);
DISPLAY 0.680851 (3062 3708);
PAINT GREEN (3062 3708);
FORCEPROP 2 LAST CDS_LIB standard
J 0
(3000 3700);
DISPLAY INVISIBLE (3000 3700);
FORCEPROP 1 LAST BODY_TYPE PLUMBING
J 2
(3000 3750);
DISPLAY 0.872340 (3000 3750);
PAINT GREEN (3000 3750);
DISPLAY INVISIBLE (3000 3750);
FORCEPROP 1 LAST HDL_TAP TRUE
J 2
(2675 3575);
DISPLAY 0.872340 (2675 3575);
DISPLAY INVISIBLE (2675 3575);
FORCEPROP 1 LAST PATH I145
J 2
(3002 3700);
DISPLAY 0.872340 (3002 3700);
PAINT GREEN (3002 3700);
DISPLAY INVISIBLE (3002 3700);
FORCEADD TAP..1
R 2
(3250 2350);
FORCEPROP 3 LASTPIN (3300 2350) SIG_NAME P5E_CPU0_P1_TX_DN<8>
J 0
(3310 2360);
DISPLAY 0.659574 (3310 2360);
PAINT MONO (3310 2360);
DISPLAY INVISIBLE (3310 2360);
FORCEPROP 1 LASTPIN (3300 2350) BN 8
J 2
(3312 2358);
DISPLAY 0.680851 (3312 2358);
PAINT GREEN (3312 2358);
FORCEPROP 2 LAST CDS_LIB standard
J 0
(3250 2350);
DISPLAY INVISIBLE (3250 2350);
FORCEPROP 1 LAST BODY_TYPE PLUMBING
J 2
(3250 2400);
DISPLAY 0.872340 (3250 2400);
PAINT GREEN (3250 2400);
DISPLAY INVISIBLE (3250 2400);
FORCEPROP 1 LAST HDL_TAP TRUE
J 2
(2925 2225);
DISPLAY 0.872340 (2925 2225);
DISPLAY INVISIBLE (2925 2225);
FORCEPROP 1 LAST PATH I146
J 2
(3252 2350);
DISPLAY 0.872340 (3252 2350);
PAINT GREEN (3252 2350);
DISPLAY INVISIBLE (3252 2350);
FORCEADD TAP..1
R 2
(3250 2550);
FORCEPROP 3 LASTPIN (3300 2550) SIG_NAME P5E_CPU0_P1_TX_DN<9>
J 0
(3310 2560);
DISPLAY 0.659574 (3310 2560);
PAINT MONO (3310 2560);
DISPLAY INVISIBLE (3310 2560);
FORCEPROP 1 LASTPIN (3300 2550) BN 9
J 2
(3312 2558);
DISPLAY 0.680851 (3312 2558);
PAINT GREEN (3312 2558);
FORCEPROP 2 LAST CDS_LIB standard
J 0
(3250 2550);
DISPLAY INVISIBLE (3250 2550);
FORCEPROP 1 LAST BODY_TYPE PLUMBING
J 2
(3250 2600);
DISPLAY 0.872340 (3250 2600);
PAINT GREEN (3250 2600);
DISPLAY INVISIBLE (3250 2600);
FORCEPROP 1 LAST HDL_TAP TRUE
J 2
(2925 2425);
DISPLAY 0.872340 (2925 2425);
DISPLAY INVISIBLE (2925 2425);
FORCEPROP 1 LAST PATH I147
J 2
(3252 2550);
DISPLAY 0.872340 (3252 2550);
PAINT GREEN (3252 2550);
DISPLAY INVISIBLE (3252 2550);
FORCEADD TAP..1
R 2
(3250 2750);
FORCEPROP 3 LASTPIN (3300 2750) SIG_NAME P5E_CPU0_P1_TX_DN<10>
J 0
(3310 2760);
DISPLAY 0.659574 (3310 2760);
PAINT MONO (3310 2760);
DISPLAY INVISIBLE (3310 2760);
FORCEPROP 1 LASTPIN (3300 2750) BN 10
J 2
(3312 2758);
DISPLAY 0.680851 (3312 2758);
PAINT GREEN (3312 2758);
FORCEPROP 2 LAST CDS_LIB standard
J 0
(3250 2750);
DISPLAY INVISIBLE (3250 2750);
FORCEPROP 1 LAST BODY_TYPE PLUMBING
J 2
(3250 2800);
DISPLAY 0.872340 (3250 2800);
PAINT GREEN (3250 2800);
DISPLAY INVISIBLE (3250 2800);
FORCEPROP 1 LAST HDL_TAP TRUE
J 2
(2925 2625);
DISPLAY 0.872340 (2925 2625);
DISPLAY INVISIBLE (2925 2625);
FORCEPROP 1 LAST PATH I148
J 2
(3252 2750);
DISPLAY 0.872340 (3252 2750);
PAINT GREEN (3252 2750);
DISPLAY INVISIBLE (3252 2750);
FORCEADD TAP..1
R 2
(3250 2950);
FORCEPROP 3 LASTPIN (3300 2950) SIG_NAME P5E_CPU0_P1_TX_DN<11>
J 0
(3310 2960);
DISPLAY 0.659574 (3310 2960);
PAINT MONO (3310 2960);
DISPLAY INVISIBLE (3310 2960);
FORCEPROP 1 LASTPIN (3300 2950) BN 11
J 2
(3312 2958);
DISPLAY 0.680851 (3312 2958);
PAINT GREEN (3312 2958);
FORCEPROP 2 LAST CDS_LIB standard
J 0
(3250 2950);
DISPLAY INVISIBLE (3250 2950);
FORCEPROP 1 LAST BODY_TYPE PLUMBING
J 2
(3250 3000);
DISPLAY 0.872340 (3250 3000);
PAINT GREEN (3250 3000);
DISPLAY INVISIBLE (3250 3000);
FORCEPROP 1 LAST HDL_TAP TRUE
J 2
(2925 2825);
DISPLAY 0.872340 (2925 2825);
DISPLAY INVISIBLE (2925 2825);
FORCEPROP 1 LAST PATH I149
J 2
(3252 2950);
DISPLAY 0.872340 (3252 2950);
PAINT GREEN (3252 2950);
DISPLAY INVISIBLE (3252 2950);
FORCEADD TAP..1
R 2
(-1550 1525);
FORCEPROP 3 LASTPIN (-1500 1525) SIG_NAME P5E_CPU0_P0_TX_DP<6>
J 0
(-1490 1535);
DISPLAY 0.659574 (-1490 1535);
PAINT MONO (-1490 1535);
DISPLAY INVISIBLE (-1490 1535);
FORCEPROP 1 LASTPIN (-1500 1525) BN 6
J 2
(-1488 1533);
DISPLAY 0.680851 (-1488 1533);
PAINT GREEN (-1488 1533);
FORCEPROP 2 LAST CDS_LIB standard
J 0
(-1550 1525);
DISPLAY INVISIBLE (-1550 1525);
FORCEPROP 1 LAST BODY_TYPE PLUMBING
J 2
(-1550 1575);
DISPLAY 0.872340 (-1550 1575);
PAINT GREEN (-1550 1575);
DISPLAY INVISIBLE (-1550 1575);
FORCEPROP 1 LAST HDL_TAP TRUE
J 2
(-1875 1400);
DISPLAY 0.872340 (-1875 1400);
DISPLAY INVISIBLE (-1875 1400);
FORCEPROP 1 LAST PATH I15
J 2
(-1548 1525);
DISPLAY 0.872340 (-1548 1525);
PAINT GREEN (-1548 1525);
DISPLAY INVISIBLE (-1548 1525);
FORCEADD TAP..1
R 2
(3250 3150);
FORCEPROP 3 LASTPIN (3300 3150) SIG_NAME P5E_CPU0_P1_TX_DN<12>
J 0
(3310 3160);
DISPLAY 0.659574 (3310 3160);
PAINT MONO (3310 3160);
DISPLAY INVISIBLE (3310 3160);
FORCEPROP 1 LASTPIN (3300 3150) BN 12
J 2
(3312 3158);
DISPLAY 0.680851 (3312 3158);
PAINT GREEN (3312 3158);
FORCEPROP 2 LAST CDS_LIB standard
J 0
(3250 3150);
DISPLAY INVISIBLE (3250 3150);
FORCEPROP 1 LAST BODY_TYPE PLUMBING
J 2
(3250 3200);
DISPLAY 0.872340 (3250 3200);
PAINT GREEN (3250 3200);
DISPLAY INVISIBLE (3250 3200);
FORCEPROP 1 LAST HDL_TAP TRUE
J 2
(2925 3025);
DISPLAY 0.872340 (2925 3025);
DISPLAY INVISIBLE (2925 3025);
FORCEPROP 1 LAST PATH I150
J 2
(3252 3150);
DISPLAY 0.872340 (3252 3150);
PAINT GREEN (3252 3150);
DISPLAY INVISIBLE (3252 3150);
FORCEADD Q_CAP_DIFFBUS..2
R 2
(3975 2300);
FORCEPROP 1 LAST LOCATION C949
J 2
(4209 2317);
DISPLAY 0.723404 (4209 2317);
PAINT GREEN (4209 2317);
FORCEPROP 2 LAST $SEC 1
J 2
(4150 2375);
DISPLAY 0.680851 (4150 2375);
PAINT MONO (4150 2375);
DISPLAY INVISIBLE (4150 2375);
FORCEPROP 2 LAST CDS_SEC 1
J 2
(4150 2375);
DISPLAY 0.680851 (4150 2375);
DISPLAY INVISIBLE (4150 2375);
FORCEPROP 2 LASTPIN (4050 2300) $PN 1
J 0
(4060 2310);
DISPLAY 0.808511 (4060 2310);
FORCEPROP 2 LASTPIN (3900 2300) $PN 2
J 2
(3890 2310);
DISPLAY 0.808511 (3890 2310);
FORCEPROP 2 LAST VALUE DIFF BUS_0.22UF
J 2
(3825 2300);
DISPLAY 0.553191 (3825 2300);
FORCEPROP 1 LAST CDS_LMAN_SYM_OUTLINE -25,50,25,-50
J 2
(3975 2300);
DISPLAY 0.468085 (3975 2300);
PAINT GREEN (3975 2300);
DISPLAY INVISIBLE (3975 2300);
FORCEPROP 2 LAST CDS_LIB pure_quanta
J 2
(3975 2300);
DISPLAY INVISIBLE (3975 2300);
FORCEPROP 1 LAST PIN_NAMES_ROTATE TRUE
J 2
(3975 2300);
DISPLAY 0.489362 (3975 2300);
PAINT GREEN (3975 2300);
DISPLAY INVISIBLE (3975 2300);
FORCEPROP 2 LAST VOLTAGE 6.3V
J 2
(3625 2350);
DISPLAY 0.553191 (3625 2350);
DISPLAY INVISIBLE (3625 2350);
FORCEPROP 1 LAST MATERIAL X6S
J 2
(3984 2379);
DISPLAY 0.574468 (3984 2379);
PAINT GREEN (3984 2379);
DISPLAY INVISIBLE (3984 2379);
FORCEPROP 2 LAST PACK_TYPE C0201
J 2
(3800 2350);
DISPLAY 0.553191 (3800 2350);
DISPLAY INVISIBLE (3800 2350);
FORCEPROP 2 LAST TOLERANCE 20%
J 2
(3900 2350);
DISPLAY 0.553191 (3900 2350);
DISPLAY INVISIBLE (3900 2350);
FORCEPROP 1 LAST PART_NUMBER SP_CH4221MEE01
J 2
(3859 2388);
DISPLAY 0.574468 (3859 2388);
PAINT GREEN (3859 2388);
DISPLAY INVISIBLE (3859 2388);
FORCEPROP 1 LAST LOCATION C949
J 0
(4225 2375);
DISPLAY 1.021277 (4225 2375);
DISPLAY INVISIBLE (4225 2375);
FORCEPROP 1 LAST PATH I151
J 2
(3975 2300);
DISPLAY 0.723404 (3975 2300);
DISPLAY INVISIBLE (3975 2300);
FORCEADD Q_CAP_DIFFBUS..2
R 2
(3975 2350);
FORCEPROP 1 LAST LOCATION C948
J 2
(4209 2367);
DISPLAY 0.723404 (4209 2367);
PAINT GREEN (4209 2367);
FORCEPROP 2 LAST $SEC 1
J 2
(4150 2425);
DISPLAY 0.680851 (4150 2425);
PAINT MONO (4150 2425);
DISPLAY INVISIBLE (4150 2425);
FORCEPROP 2 LAST CDS_SEC 1
J 2
(4150 2425);
DISPLAY 0.680851 (4150 2425);
DISPLAY INVISIBLE (4150 2425);
FORCEPROP 2 LASTPIN (4050 2350) $PN 1
J 0
(4060 2360);
DISPLAY 0.808511 (4060 2360);
FORCEPROP 2 LASTPIN (3900 2350) $PN 2
J 2
(3890 2360);
DISPLAY 0.808511 (3890 2360);
FORCEPROP 2 LAST VALUE DIFF BUS_0.22UF
J 2
(3825 2350);
DISPLAY 0.553191 (3825 2350);
FORCEPROP 1 LAST CDS_LMAN_SYM_OUTLINE -25,50,25,-50
J 2
(3975 2350);
DISPLAY 0.468085 (3975 2350);
PAINT GREEN (3975 2350);
DISPLAY INVISIBLE (3975 2350);
FORCEPROP 2 LAST CDS_LIB pure_quanta
J 2
(3975 2350);
DISPLAY INVISIBLE (3975 2350);
FORCEPROP 1 LAST PIN_NAMES_ROTATE TRUE
J 2
(3975 2350);
DISPLAY 0.489362 (3975 2350);
PAINT GREEN (3975 2350);
DISPLAY INVISIBLE (3975 2350);
FORCEPROP 2 LAST VOLTAGE 6.3V
J 2
(3625 2400);
DISPLAY 0.553191 (3625 2400);
DISPLAY INVISIBLE (3625 2400);
FORCEPROP 1 LAST MATERIAL X6S
J 2
(3984 2429);
DISPLAY 0.574468 (3984 2429);
PAINT GREEN (3984 2429);
DISPLAY INVISIBLE (3984 2429);
FORCEPROP 2 LAST PACK_TYPE C0201
J 2
(3800 2400);
DISPLAY 0.553191 (3800 2400);
DISPLAY INVISIBLE (3800 2400);
FORCEPROP 2 LAST TOLERANCE 20%
J 2
(3900 2400);
DISPLAY 0.553191 (3900 2400);
DISPLAY INVISIBLE (3900 2400);
FORCEPROP 1 LAST PART_NUMBER SP_CH4221MEE01
J 2
(3859 2438);
DISPLAY 0.574468 (3859 2438);
PAINT GREEN (3859 2438);
DISPLAY INVISIBLE (3859 2438);
FORCEPROP 1 LAST LOCATION C948
J 0
(4225 2425);
DISPLAY 1.021277 (4225 2425);
DISPLAY INVISIBLE (4225 2425);
FORCEPROP 1 LAST PATH I152
J 2
(3975 2350);
DISPLAY 0.723404 (3975 2350);
DISPLAY INVISIBLE (3975 2350);
FORCEADD Q_CAP_DIFFBUS..2
R 2
(3975 2500);
FORCEPROP 1 LAST LOCATION C947
J 2
(4209 2517);
DISPLAY 0.723404 (4209 2517);
PAINT GREEN (4209 2517);
FORCEPROP 2 LAST $SEC 1
J 2
(4150 2575);
DISPLAY 0.680851 (4150 2575);
PAINT MONO (4150 2575);
DISPLAY INVISIBLE (4150 2575);
FORCEPROP 2 LAST CDS_SEC 1
J 2
(4150 2575);
DISPLAY 0.680851 (4150 2575);
DISPLAY INVISIBLE (4150 2575);
FORCEPROP 2 LASTPIN (4050 2500) $PN 1
J 0
(4060 2510);
DISPLAY 0.808511 (4060 2510);
FORCEPROP 2 LASTPIN (3900 2500) $PN 2
J 2
(3890 2510);
DISPLAY 0.808511 (3890 2510);
FORCEPROP 2 LAST VALUE DIFF BUS_0.22UF
J 2
(3825 2500);
DISPLAY 0.553191 (3825 2500);
FORCEPROP 1 LAST CDS_LMAN_SYM_OUTLINE -25,50,25,-50
J 2
(3975 2500);
DISPLAY 0.468085 (3975 2500);
PAINT GREEN (3975 2500);
DISPLAY INVISIBLE (3975 2500);
FORCEPROP 2 LAST CDS_LIB pure_quanta
J 2
(3975 2500);
DISPLAY INVISIBLE (3975 2500);
FORCEPROP 1 LAST PIN_NAMES_ROTATE TRUE
J 2
(3975 2500);
DISPLAY 0.489362 (3975 2500);
PAINT GREEN (3975 2500);
DISPLAY INVISIBLE (3975 2500);
FORCEPROP 2 LAST VOLTAGE 6.3V
J 2
(3625 2550);
DISPLAY 0.553191 (3625 2550);
DISPLAY INVISIBLE (3625 2550);
FORCEPROP 1 LAST MATERIAL X6S
J 2
(3984 2579);
DISPLAY 0.574468 (3984 2579);
PAINT GREEN (3984 2579);
DISPLAY INVISIBLE (3984 2579);
FORCEPROP 2 LAST PACK_TYPE C0201
J 2
(3800 2550);
DISPLAY 0.553191 (3800 2550);
DISPLAY INVISIBLE (3800 2550);
FORCEPROP 2 LAST TOLERANCE 20%
J 2
(3900 2550);
DISPLAY 0.553191 (3900 2550);
DISPLAY INVISIBLE (3900 2550);
FORCEPROP 1 LAST PART_NUMBER SP_CH4221MEE01
J 2
(3859 2588);
DISPLAY 0.574468 (3859 2588);
PAINT GREEN (3859 2588);
DISPLAY INVISIBLE (3859 2588);
FORCEPROP 1 LAST LOCATION C947
J 0
(4225 2575);
DISPLAY 1.021277 (4225 2575);
DISPLAY INVISIBLE (4225 2575);
FORCEPROP 1 LAST PATH I153
J 2
(3975 2500);
DISPLAY 0.723404 (3975 2500);
DISPLAY INVISIBLE (3975 2500);
FORCEADD Q_CAP_DIFFBUS..2
R 2
(3975 2550);
FORCEPROP 1 LAST LOCATION C946
J 2
(4209 2567);
DISPLAY 0.723404 (4209 2567);
PAINT GREEN (4209 2567);
FORCEPROP 2 LAST $SEC 1
J 2
(4150 2625);
DISPLAY 0.680851 (4150 2625);
PAINT MONO (4150 2625);
DISPLAY INVISIBLE (4150 2625);
FORCEPROP 2 LAST CDS_SEC 1
J 2
(4150 2625);
DISPLAY 0.680851 (4150 2625);
DISPLAY INVISIBLE (4150 2625);
FORCEPROP 2 LASTPIN (4050 2550) $PN 1
J 0
(4060 2560);
DISPLAY 0.808511 (4060 2560);
FORCEPROP 2 LASTPIN (3900 2550) $PN 2
J 2
(3890 2560);
DISPLAY 0.808511 (3890 2560);
FORCEPROP 2 LAST VALUE DIFF BUS_0.22UF
J 2
(3825 2550);
DISPLAY 0.553191 (3825 2550);
FORCEPROP 2 LAST CDS_LIB pure_quanta
J 2
(3975 2550);
DISPLAY INVISIBLE (3975 2550);
FORCEPROP 1 LAST CDS_LMAN_SYM_OUTLINE -25,50,25,-50
J 2
(3975 2550);
DISPLAY 0.468085 (3975 2550);
PAINT GREEN (3975 2550);
DISPLAY INVISIBLE (3975 2550);
FORCEPROP 1 LAST PIN_NAMES_ROTATE TRUE
J 2
(3975 2550);
DISPLAY 0.489362 (3975 2550);
PAINT GREEN (3975 2550);
DISPLAY INVISIBLE (3975 2550);
FORCEPROP 2 LAST VOLTAGE 6.3V
J 2
(3625 2600);
DISPLAY 0.553191 (3625 2600);
DISPLAY INVISIBLE (3625 2600);
FORCEPROP 1 LAST MATERIAL X6S
J 2
(3984 2629);
DISPLAY 0.574468 (3984 2629);
PAINT GREEN (3984 2629);
DISPLAY INVISIBLE (3984 2629);
FORCEPROP 2 LAST PACK_TYPE C0201
J 2
(3800 2600);
DISPLAY 0.553191 (3800 2600);
DISPLAY INVISIBLE (3800 2600);
FORCEPROP 2 LAST TOLERANCE 20%
J 2
(3900 2600);
DISPLAY 0.553191 (3900 2600);
DISPLAY INVISIBLE (3900 2600);
FORCEPROP 1 LAST PART_NUMBER SP_CH4221MEE01
J 2
(3859 2638);
DISPLAY 0.574468 (3859 2638);
PAINT GREEN (3859 2638);
DISPLAY INVISIBLE (3859 2638);
FORCEPROP 1 LAST LOCATION C946
J 0
(4225 2625);
DISPLAY 1.021277 (4225 2625);
DISPLAY INVISIBLE (4225 2625);
FORCEPROP 1 LAST PATH I154
J 2
(3975 2550);
DISPLAY 0.723404 (3975 2550);
DISPLAY INVISIBLE (3975 2550);
FORCEADD Q_CAP_DIFFBUS..2
R 2
(3975 2700);
FORCEPROP 1 LAST LOCATION C945
J 2
(4209 2717);
DISPLAY 0.723404 (4209 2717);
PAINT GREEN (4209 2717);
FORCEPROP 2 LAST $SEC 1
J 2
(4150 2775);
DISPLAY 0.680851 (4150 2775);
PAINT MONO (4150 2775);
DISPLAY INVISIBLE (4150 2775);
FORCEPROP 2 LAST CDS_SEC 1
J 2
(4150 2775);
DISPLAY 0.680851 (4150 2775);
DISPLAY INVISIBLE (4150 2775);
FORCEPROP 2 LASTPIN (4050 2700) $PN 1
J 0
(4060 2710);
DISPLAY 0.808511 (4060 2710);
FORCEPROP 2 LASTPIN (3900 2700) $PN 2
J 2
(3890 2710);
DISPLAY 0.808511 (3890 2710);
FORCEPROP 2 LAST VALUE DIFF BUS_0.22UF
J 2
(3825 2700);
DISPLAY 0.553191 (3825 2700);
FORCEPROP 1 LAST CDS_LMAN_SYM_OUTLINE -25,50,25,-50
J 2
(3975 2700);
DISPLAY 0.468085 (3975 2700);
PAINT GREEN (3975 2700);
DISPLAY INVISIBLE (3975 2700);
FORCEPROP 2 LAST CDS_LIB pure_quanta
J 2
(3975 2700);
DISPLAY INVISIBLE (3975 2700);
FORCEPROP 1 LAST PIN_NAMES_ROTATE TRUE
J 2
(3975 2700);
DISPLAY 0.489362 (3975 2700);
PAINT GREEN (3975 2700);
DISPLAY INVISIBLE (3975 2700);
FORCEPROP 2 LAST VOLTAGE 6.3V
J 2
(3625 2750);
DISPLAY 0.553191 (3625 2750);
DISPLAY INVISIBLE (3625 2750);
FORCEPROP 1 LAST MATERIAL X6S
J 2
(3984 2779);
DISPLAY 0.574468 (3984 2779);
PAINT GREEN (3984 2779);
DISPLAY INVISIBLE (3984 2779);
FORCEPROP 2 LAST PACK_TYPE C0201
J 2
(3800 2750);
DISPLAY 0.553191 (3800 2750);
DISPLAY INVISIBLE (3800 2750);
FORCEPROP 2 LAST TOLERANCE 20%
J 2
(3900 2750);
DISPLAY 0.553191 (3900 2750);
DISPLAY INVISIBLE (3900 2750);
FORCEPROP 1 LAST PART_NUMBER SP_CH4221MEE01
J 2
(3859 2788);
DISPLAY 0.574468 (3859 2788);
PAINT GREEN (3859 2788);
DISPLAY INVISIBLE (3859 2788);
FORCEPROP 1 LAST LOCATION C945
J 0
(4225 2775);
DISPLAY 1.021277 (4225 2775);
DISPLAY INVISIBLE (4225 2775);
FORCEPROP 1 LAST PATH I155
J 2
(3975 2700);
DISPLAY 0.723404 (3975 2700);
DISPLAY INVISIBLE (3975 2700);
FORCEADD Q_CAP_DIFFBUS..2
R 2
(3975 2750);
FORCEPROP 1 LAST LOCATION C944
J 2
(4209 2767);
DISPLAY 0.723404 (4209 2767);
PAINT GREEN (4209 2767);
FORCEPROP 2 LAST $SEC 1
J 2
(4150 2825);
DISPLAY 0.680851 (4150 2825);
PAINT MONO (4150 2825);
DISPLAY INVISIBLE (4150 2825);
FORCEPROP 2 LAST CDS_SEC 1
J 2
(4150 2825);
DISPLAY 0.680851 (4150 2825);
DISPLAY INVISIBLE (4150 2825);
FORCEPROP 2 LASTPIN (4050 2750) $PN 1
J 0
(4060 2760);
DISPLAY 0.808511 (4060 2760);
FORCEPROP 2 LASTPIN (3900 2750) $PN 2
J 2
(3890 2760);
DISPLAY 0.808511 (3890 2760);
FORCEPROP 2 LAST VALUE DIFF BUS_0.22UF
J 2
(3825 2750);
DISPLAY 0.553191 (3825 2750);
FORCEPROP 1 LAST CDS_LMAN_SYM_OUTLINE -25,50,25,-50
J 2
(3975 2750);
DISPLAY 0.468085 (3975 2750);
PAINT GREEN (3975 2750);
DISPLAY INVISIBLE (3975 2750);
FORCEPROP 2 LAST CDS_LIB pure_quanta
J 2
(3975 2750);
DISPLAY INVISIBLE (3975 2750);
FORCEPROP 1 LAST PIN_NAMES_ROTATE TRUE
J 2
(3975 2750);
DISPLAY 0.489362 (3975 2750);
PAINT GREEN (3975 2750);
DISPLAY INVISIBLE (3975 2750);
FORCEPROP 2 LAST VOLTAGE 6.3V
J 2
(3625 2800);
DISPLAY 0.553191 (3625 2800);
DISPLAY INVISIBLE (3625 2800);
FORCEPROP 1 LAST MATERIAL X6S
J 2
(3984 2829);
DISPLAY 0.574468 (3984 2829);
PAINT GREEN (3984 2829);
DISPLAY INVISIBLE (3984 2829);
FORCEPROP 2 LAST PACK_TYPE C0201
J 2
(3800 2800);
DISPLAY 0.553191 (3800 2800);
DISPLAY INVISIBLE (3800 2800);
FORCEPROP 2 LAST TOLERANCE 20%
J 2
(3900 2800);
DISPLAY 0.553191 (3900 2800);
DISPLAY INVISIBLE (3900 2800);
FORCEPROP 1 LAST PART_NUMBER SP_CH4221MEE01
J 2
(3859 2838);
DISPLAY 0.574468 (3859 2838);
PAINT GREEN (3859 2838);
DISPLAY INVISIBLE (3859 2838);
FORCEPROP 1 LAST LOCATION C944
J 0
(4225 2825);
DISPLAY 1.021277 (4225 2825);
DISPLAY INVISIBLE (4225 2825);
FORCEPROP 1 LAST PATH I156
J 2
(3975 2750);
DISPLAY 0.723404 (3975 2750);
DISPLAY INVISIBLE (3975 2750);
FORCEADD Q_CAP_DIFFBUS..2
R 2
(3975 2900);
FORCEPROP 1 LAST LOCATION C943
J 2
(4209 2917);
DISPLAY 0.723404 (4209 2917);
PAINT GREEN (4209 2917);
FORCEPROP 2 LAST $SEC 1
J 2
(4150 2975);
DISPLAY 0.680851 (4150 2975);
PAINT MONO (4150 2975);
DISPLAY INVISIBLE (4150 2975);
FORCEPROP 2 LAST CDS_SEC 1
J 2
(4150 2975);
DISPLAY 0.680851 (4150 2975);
DISPLAY INVISIBLE (4150 2975);
FORCEPROP 2 LASTPIN (4050 2900) $PN 1
J 0
(4060 2910);
DISPLAY 0.808511 (4060 2910);
FORCEPROP 2 LASTPIN (3900 2900) $PN 2
J 2
(3890 2910);
DISPLAY 0.808511 (3890 2910);
FORCEPROP 2 LAST VALUE DIFF BUS_0.22UF
J 2
(3825 2900);
DISPLAY 0.553191 (3825 2900);
FORCEPROP 2 LAST CDS_LIB pure_quanta
J 2
(3975 2900);
DISPLAY INVISIBLE (3975 2900);
FORCEPROP 1 LAST CDS_LMAN_SYM_OUTLINE -25,50,25,-50
J 2
(3975 2900);
DISPLAY 0.468085 (3975 2900);
PAINT GREEN (3975 2900);
DISPLAY INVISIBLE (3975 2900);
FORCEPROP 1 LAST PIN_NAMES_ROTATE TRUE
J 2
(3975 2900);
DISPLAY 0.489362 (3975 2900);
PAINT GREEN (3975 2900);
DISPLAY INVISIBLE (3975 2900);
FORCEPROP 2 LAST VOLTAGE 6.3V
J 2
(3625 2950);
DISPLAY 0.553191 (3625 2950);
DISPLAY INVISIBLE (3625 2950);
FORCEPROP 1 LAST MATERIAL X6S
J 2
(3984 2979);
DISPLAY 0.574468 (3984 2979);
PAINT GREEN (3984 2979);
DISPLAY INVISIBLE (3984 2979);
FORCEPROP 2 LAST PACK_TYPE C0201
J 2
(3800 2950);
DISPLAY 0.553191 (3800 2950);
DISPLAY INVISIBLE (3800 2950);
FORCEPROP 2 LAST TOLERANCE 20%
J 2
(3900 2950);
DISPLAY 0.553191 (3900 2950);
DISPLAY INVISIBLE (3900 2950);
FORCEPROP 1 LAST PART_NUMBER SP_CH4221MEE01
J 2
(3859 2988);
DISPLAY 0.574468 (3859 2988);
PAINT GREEN (3859 2988);
DISPLAY INVISIBLE (3859 2988);
FORCEPROP 1 LAST LOCATION C943
J 0
(4225 2975);
DISPLAY 1.021277 (4225 2975);
DISPLAY INVISIBLE (4225 2975);
FORCEPROP 1 LAST PATH I157
J 2
(3975 2900);
DISPLAY 0.723404 (3975 2900);
DISPLAY INVISIBLE (3975 2900);
FORCEADD Q_CAP_DIFFBUS..2
R 2
(3975 2950);
FORCEPROP 1 LAST LOCATION C942
J 2
(4209 2967);
DISPLAY 0.723404 (4209 2967);
PAINT GREEN (4209 2967);
FORCEPROP 2 LAST $SEC 1
J 2
(4150 3025);
DISPLAY 0.680851 (4150 3025);
PAINT MONO (4150 3025);
DISPLAY INVISIBLE (4150 3025);
FORCEPROP 2 LAST CDS_SEC 1
J 2
(4150 3025);
DISPLAY 0.680851 (4150 3025);
DISPLAY INVISIBLE (4150 3025);
FORCEPROP 2 LASTPIN (4050 2950) $PN 1
J 0
(4060 2960);
DISPLAY 0.808511 (4060 2960);
FORCEPROP 2 LASTPIN (3900 2950) $PN 2
J 2
(3890 2960);
DISPLAY 0.808511 (3890 2960);
FORCEPROP 2 LAST VALUE DIFF BUS_0.22UF
J 2
(3825 2950);
DISPLAY 0.553191 (3825 2950);
FORCEPROP 2 LAST CDS_LIB pure_quanta
J 2
(3975 2950);
DISPLAY INVISIBLE (3975 2950);
FORCEPROP 1 LAST CDS_LMAN_SYM_OUTLINE -25,50,25,-50
J 2
(3975 2950);
DISPLAY 0.468085 (3975 2950);
PAINT GREEN (3975 2950);
DISPLAY INVISIBLE (3975 2950);
FORCEPROP 1 LAST PIN_NAMES_ROTATE TRUE
J 2
(3975 2950);
DISPLAY 0.489362 (3975 2950);
PAINT GREEN (3975 2950);
DISPLAY INVISIBLE (3975 2950);
FORCEPROP 2 LAST VOLTAGE 6.3V
J 2
(3625 3000);
DISPLAY 0.553191 (3625 3000);
DISPLAY INVISIBLE (3625 3000);
FORCEPROP 1 LAST MATERIAL X6S
J 2
(3984 3029);
DISPLAY 0.574468 (3984 3029);
PAINT GREEN (3984 3029);
DISPLAY INVISIBLE (3984 3029);
FORCEPROP 2 LAST PACK_TYPE C0201
J 2
(3800 3000);
DISPLAY 0.553191 (3800 3000);
DISPLAY INVISIBLE (3800 3000);
FORCEPROP 2 LAST TOLERANCE 20%
J 2
(3900 3000);
DISPLAY 0.553191 (3900 3000);
DISPLAY INVISIBLE (3900 3000);
FORCEPROP 1 LAST PART_NUMBER SP_CH4221MEE01
J 2
(3859 3038);
DISPLAY 0.574468 (3859 3038);
PAINT GREEN (3859 3038);
DISPLAY INVISIBLE (3859 3038);
FORCEPROP 1 LAST LOCATION C942
J 0
(4225 3025);
DISPLAY 1.021277 (4225 3025);
DISPLAY INVISIBLE (4225 3025);
FORCEPROP 1 LAST PATH I158
J 2
(3975 2950);
DISPLAY 0.723404 (3975 2950);
DISPLAY INVISIBLE (3975 2950);
FORCEADD Q_CAP_DIFFBUS..2
R 2
(3975 3100);
FORCEPROP 1 LAST LOCATION C941
J 2
(4209 3117);
DISPLAY 0.723404 (4209 3117);
PAINT GREEN (4209 3117);
FORCEPROP 2 LAST $SEC 1
J 2
(4150 3175);
DISPLAY 0.680851 (4150 3175);
PAINT MONO (4150 3175);
DISPLAY INVISIBLE (4150 3175);
FORCEPROP 2 LAST CDS_SEC 1
J 2
(4150 3175);
DISPLAY 0.680851 (4150 3175);
DISPLAY INVISIBLE (4150 3175);
FORCEPROP 2 LASTPIN (4050 3100) $PN 1
J 0
(4060 3110);
DISPLAY 0.808511 (4060 3110);
FORCEPROP 2 LASTPIN (3900 3100) $PN 2
J 2
(3890 3110);
DISPLAY 0.808511 (3890 3110);
FORCEPROP 2 LAST VALUE DIFF BUS_0.22UF
J 2
(3825 3100);
DISPLAY 0.553191 (3825 3100);
FORCEPROP 1 LAST CDS_LMAN_SYM_OUTLINE -25,50,25,-50
J 2
(3975 3100);
DISPLAY 0.468085 (3975 3100);
PAINT GREEN (3975 3100);
DISPLAY INVISIBLE (3975 3100);
FORCEPROP 2 LAST CDS_LIB pure_quanta
J 2
(3975 3100);
DISPLAY INVISIBLE (3975 3100);
FORCEPROP 1 LAST PIN_NAMES_ROTATE TRUE
J 2
(3975 3100);
DISPLAY 0.489362 (3975 3100);
PAINT GREEN (3975 3100);
DISPLAY INVISIBLE (3975 3100);
FORCEPROP 2 LAST VOLTAGE 6.3V
J 2
(3625 3150);
DISPLAY 0.553191 (3625 3150);
DISPLAY INVISIBLE (3625 3150);
FORCEPROP 1 LAST MATERIAL X6S
J 2
(3984 3179);
DISPLAY 0.574468 (3984 3179);
PAINT GREEN (3984 3179);
DISPLAY INVISIBLE (3984 3179);
FORCEPROP 2 LAST PACK_TYPE C0201
J 2
(3800 3150);
DISPLAY 0.553191 (3800 3150);
DISPLAY INVISIBLE (3800 3150);
FORCEPROP 2 LAST TOLERANCE 20%
J 2
(3900 3150);
DISPLAY 0.553191 (3900 3150);
DISPLAY INVISIBLE (3900 3150);
FORCEPROP 1 LAST PART_NUMBER SP_CH4221MEE01
J 2
(3859 3188);
DISPLAY 0.574468 (3859 3188);
PAINT GREEN (3859 3188);
DISPLAY INVISIBLE (3859 3188);
FORCEPROP 1 LAST LOCATION C941
J 0
(4225 3175);
DISPLAY 1.021277 (4225 3175);
DISPLAY INVISIBLE (4225 3175);
FORCEPROP 1 LAST PATH I159
J 2
(3975 3100);
DISPLAY 0.723404 (3975 3100);
DISPLAY INVISIBLE (3975 3100);
FORCEADD TAP..1
R 2
(-1300 1175);
FORCEPROP 3 LASTPIN (-1250 1175) SIG_NAME P5E_CPU0_P0_TX_DN<4>
J 0
(-1240 1185);
DISPLAY 0.659574 (-1240 1185);
PAINT MONO (-1240 1185);
DISPLAY INVISIBLE (-1240 1185);
FORCEPROP 1 LASTPIN (-1250 1175) BN 4
J 2
(-1238 1183);
DISPLAY 0.680851 (-1238 1183);
PAINT GREEN (-1238 1183);
FORCEPROP 2 LAST CDS_LIB standard
J 0
(-1300 1175);
DISPLAY INVISIBLE (-1300 1175);
FORCEPROP 1 LAST BODY_TYPE PLUMBING
J 2
(-1300 1225);
DISPLAY 0.872340 (-1300 1225);
PAINT GREEN (-1300 1225);
DISPLAY INVISIBLE (-1300 1225);
FORCEPROP 1 LAST HDL_TAP TRUE
J 2
(-1625 1050);
DISPLAY 0.872340 (-1625 1050);
DISPLAY INVISIBLE (-1625 1050);
FORCEPROP 1 LAST PATH I16
J 2
(-1298 1175);
DISPLAY 0.872340 (-1298 1175);
PAINT GREEN (-1298 1175);
DISPLAY INVISIBLE (-1298 1175);
FORCEADD Q_CAP_DIFFBUS..2
R 2
(3975 3150);
FORCEPROP 1 LAST LOCATION C940
J 2
(4209 3167);
DISPLAY 0.723404 (4209 3167);
PAINT GREEN (4209 3167);
FORCEPROP 2 LAST $SEC 1
J 2
(4150 3225);
DISPLAY 0.680851 (4150 3225);
PAINT MONO (4150 3225);
DISPLAY INVISIBLE (4150 3225);
FORCEPROP 2 LAST CDS_SEC 1
J 2
(4150 3225);
DISPLAY 0.680851 (4150 3225);
DISPLAY INVISIBLE (4150 3225);
FORCEPROP 2 LASTPIN (4050 3150) $PN 1
J 0
(4060 3160);
DISPLAY 0.808511 (4060 3160);
FORCEPROP 2 LASTPIN (3900 3150) $PN 2
J 2
(3890 3160);
DISPLAY 0.808511 (3890 3160);
FORCEPROP 2 LAST VALUE DIFF BUS_0.22UF
J 2
(3825 3150);
DISPLAY 0.553191 (3825 3150);
FORCEPROP 1 LAST CDS_LMAN_SYM_OUTLINE -25,50,25,-50
J 2
(3975 3150);
DISPLAY 0.468085 (3975 3150);
PAINT GREEN (3975 3150);
DISPLAY INVISIBLE (3975 3150);
FORCEPROP 2 LAST CDS_LIB pure_quanta
J 2
(3975 3150);
DISPLAY INVISIBLE (3975 3150);
FORCEPROP 1 LAST PIN_NAMES_ROTATE TRUE
J 2
(3975 3150);
DISPLAY 0.489362 (3975 3150);
PAINT GREEN (3975 3150);
DISPLAY INVISIBLE (3975 3150);
FORCEPROP 2 LAST VOLTAGE 6.3V
J 2
(3625 3200);
DISPLAY 0.553191 (3625 3200);
DISPLAY INVISIBLE (3625 3200);
FORCEPROP 1 LAST MATERIAL X6S
J 2
(3984 3229);
DISPLAY 0.574468 (3984 3229);
PAINT GREEN (3984 3229);
DISPLAY INVISIBLE (3984 3229);
FORCEPROP 2 LAST PACK_TYPE C0201
J 2
(3800 3200);
DISPLAY 0.553191 (3800 3200);
DISPLAY INVISIBLE (3800 3200);
FORCEPROP 2 LAST TOLERANCE 20%
J 2
(3900 3200);
DISPLAY 0.553191 (3900 3200);
DISPLAY INVISIBLE (3900 3200);
FORCEPROP 1 LAST PART_NUMBER SP_CH4221MEE01
J 2
(3859 3238);
DISPLAY 0.574468 (3859 3238);
PAINT GREEN (3859 3238);
DISPLAY INVISIBLE (3859 3238);
FORCEPROP 1 LAST LOCATION C940
J 0
(4225 3225);
DISPLAY 1.021277 (4225 3225);
DISPLAY INVISIBLE (4225 3225);
FORCEPROP 1 LAST PATH I160
J 2
(3975 3150);
DISPLAY 0.723404 (3975 3150);
DISPLAY INVISIBLE (3975 3150);
FORCEADD TAP..1
R 2
(3250 3350);
FORCEPROP 3 LASTPIN (3300 3350) SIG_NAME P5E_CPU0_P1_TX_DN<13>
J 0
(3310 3360);
DISPLAY 0.659574 (3310 3360);
PAINT MONO (3310 3360);
DISPLAY INVISIBLE (3310 3360);
FORCEPROP 1 LASTPIN (3300 3350) BN 13
J 2
(3312 3358);
DISPLAY 0.680851 (3312 3358);
PAINT GREEN (3312 3358);
FORCEPROP 2 LAST CDS_LIB standard
J 0
(3250 3350);
DISPLAY INVISIBLE (3250 3350);
FORCEPROP 1 LAST BODY_TYPE PLUMBING
J 2
(3250 3400);
DISPLAY 0.872340 (3250 3400);
PAINT GREEN (3250 3400);
DISPLAY INVISIBLE (3250 3400);
FORCEPROP 1 LAST HDL_TAP TRUE
J 2
(2925 3225);
DISPLAY 0.872340 (2925 3225);
DISPLAY INVISIBLE (2925 3225);
FORCEPROP 1 LAST PATH I161
J 2
(3252 3350);
DISPLAY 0.872340 (3252 3350);
PAINT GREEN (3252 3350);
DISPLAY INVISIBLE (3252 3350);
FORCEADD TAP..1
R 2
(3250 3550);
FORCEPROP 3 LASTPIN (3300 3550) SIG_NAME P5E_CPU0_P1_TX_DN<14>
J 0
(3310 3560);
DISPLAY 0.659574 (3310 3560);
PAINT MONO (3310 3560);
DISPLAY INVISIBLE (3310 3560);
FORCEPROP 1 LASTPIN (3300 3550) BN 14
J 2
(3312 3558);
DISPLAY 0.680851 (3312 3558);
PAINT GREEN (3312 3558);
FORCEPROP 2 LAST CDS_LIB standard
J 0
(3250 3550);
DISPLAY INVISIBLE (3250 3550);
FORCEPROP 1 LAST BODY_TYPE PLUMBING
J 2
(3250 3600);
DISPLAY 0.872340 (3250 3600);
PAINT GREEN (3250 3600);
DISPLAY INVISIBLE (3250 3600);
FORCEPROP 1 LAST HDL_TAP TRUE
J 2
(2925 3425);
DISPLAY 0.872340 (2925 3425);
DISPLAY INVISIBLE (2925 3425);
FORCEPROP 1 LAST PATH I162
J 2
(3252 3550);
DISPLAY 0.872340 (3252 3550);
PAINT GREEN (3252 3550);
DISPLAY INVISIBLE (3252 3550);
FORCEADD TAP..1
R 2
(3250 3750);
FORCEPROP 3 LASTPIN (3300 3750) SIG_NAME P5E_CPU0_P1_TX_DN<15>
J 0
(3310 3760);
DISPLAY 0.659574 (3310 3760);
PAINT MONO (3310 3760);
DISPLAY INVISIBLE (3310 3760);
FORCEPROP 1 LASTPIN (3300 3750) BN 15
J 2
(3312 3758);
DISPLAY 0.680851 (3312 3758);
PAINT GREEN (3312 3758);
FORCEPROP 2 LAST CDS_LIB standard
J 0
(3250 3750);
DISPLAY INVISIBLE (3250 3750);
FORCEPROP 1 LAST BODY_TYPE PLUMBING
J 2
(3250 3800);
DISPLAY 0.872340 (3250 3800);
PAINT GREEN (3250 3800);
DISPLAY INVISIBLE (3250 3800);
FORCEPROP 1 LAST HDL_TAP TRUE
J 2
(2925 3625);
DISPLAY 0.872340 (2925 3625);
DISPLAY INVISIBLE (2925 3625);
FORCEPROP 1 LAST PATH I163
J 2
(3252 3750);
DISPLAY 0.872340 (3252 3750);
PAINT GREEN (3252 3750);
DISPLAY INVISIBLE (3252 3750);
FORCEADD Q_CAP_DIFFBUS..2
R 2
(3975 3300);
FORCEPROP 1 LAST LOCATION C939
J 2
(4209 3317);
DISPLAY 0.723404 (4209 3317);
PAINT GREEN (4209 3317);
FORCEPROP 2 LAST $SEC 1
J 2
(4150 3375);
DISPLAY 0.680851 (4150 3375);
PAINT MONO (4150 3375);
DISPLAY INVISIBLE (4150 3375);
FORCEPROP 2 LAST CDS_SEC 1
J 2
(4150 3375);
DISPLAY 0.680851 (4150 3375);
DISPLAY INVISIBLE (4150 3375);
FORCEPROP 2 LASTPIN (4050 3300) $PN 1
J 0
(4060 3310);
DISPLAY 0.808511 (4060 3310);
FORCEPROP 2 LASTPIN (3900 3300) $PN 2
J 2
(3890 3310);
DISPLAY 0.808511 (3890 3310);
FORCEPROP 2 LAST VALUE DIFF BUS_0.22UF
J 2
(3825 3300);
DISPLAY 0.553191 (3825 3300);
FORCEPROP 1 LAST CDS_LMAN_SYM_OUTLINE -25,50,25,-50
J 2
(3975 3300);
DISPLAY 0.468085 (3975 3300);
PAINT GREEN (3975 3300);
DISPLAY INVISIBLE (3975 3300);
FORCEPROP 2 LAST CDS_LIB pure_quanta
J 2
(3975 3300);
DISPLAY INVISIBLE (3975 3300);
FORCEPROP 1 LAST PIN_NAMES_ROTATE TRUE
J 2
(3975 3300);
DISPLAY 0.489362 (3975 3300);
PAINT GREEN (3975 3300);
DISPLAY INVISIBLE (3975 3300);
FORCEPROP 2 LAST VOLTAGE 6.3V
J 2
(3625 3350);
DISPLAY 0.553191 (3625 3350);
DISPLAY INVISIBLE (3625 3350);
FORCEPROP 1 LAST MATERIAL X6S
J 2
(3984 3379);
DISPLAY 0.574468 (3984 3379);
PAINT GREEN (3984 3379);
DISPLAY INVISIBLE (3984 3379);
FORCEPROP 2 LAST PACK_TYPE C0201
J 2
(3800 3350);
DISPLAY 0.553191 (3800 3350);
DISPLAY INVISIBLE (3800 3350);
FORCEPROP 2 LAST TOLERANCE 20%
J 2
(3900 3350);
DISPLAY 0.553191 (3900 3350);
DISPLAY INVISIBLE (3900 3350);
FORCEPROP 1 LAST PART_NUMBER SP_CH4221MEE01
J 2
(3859 3388);
DISPLAY 0.574468 (3859 3388);
PAINT GREEN (3859 3388);
DISPLAY INVISIBLE (3859 3388);
FORCEPROP 1 LAST LOCATION C939
J 0
(4225 3375);
DISPLAY 1.021277 (4225 3375);
DISPLAY INVISIBLE (4225 3375);
FORCEPROP 1 LAST PATH I164
J 2
(3975 3300);
DISPLAY 0.723404 (3975 3300);
DISPLAY INVISIBLE (3975 3300);
FORCEADD Q_CAP_DIFFBUS..2
R 2
(3975 3350);
FORCEPROP 1 LAST LOCATION C938
J 2
(4209 3367);
DISPLAY 0.723404 (4209 3367);
PAINT GREEN (4209 3367);
FORCEPROP 2 LAST $SEC 1
J 2
(4150 3425);
DISPLAY 0.680851 (4150 3425);
PAINT MONO (4150 3425);
DISPLAY INVISIBLE (4150 3425);
FORCEPROP 2 LAST CDS_SEC 1
J 2
(4150 3425);
DISPLAY 0.680851 (4150 3425);
DISPLAY INVISIBLE (4150 3425);
FORCEPROP 2 LASTPIN (4050 3350) $PN 1
J 0
(4060 3360);
DISPLAY 0.808511 (4060 3360);
FORCEPROP 2 LASTPIN (3900 3350) $PN 2
J 2
(3890 3360);
DISPLAY 0.808511 (3890 3360);
FORCEPROP 2 LAST VALUE DIFF BUS_0.22UF
J 2
(3825 3350);
DISPLAY 0.553191 (3825 3350);
FORCEPROP 1 LAST CDS_LMAN_SYM_OUTLINE -25,50,25,-50
J 2
(3975 3350);
DISPLAY 0.468085 (3975 3350);
PAINT GREEN (3975 3350);
DISPLAY INVISIBLE (3975 3350);
FORCEPROP 2 LAST CDS_LIB pure_quanta
J 2
(3975 3350);
DISPLAY INVISIBLE (3975 3350);
FORCEPROP 1 LAST PIN_NAMES_ROTATE TRUE
J 2
(3975 3350);
DISPLAY 0.489362 (3975 3350);
PAINT GREEN (3975 3350);
DISPLAY INVISIBLE (3975 3350);
FORCEPROP 2 LAST VOLTAGE 6.3V
J 2
(3625 3400);
DISPLAY 0.553191 (3625 3400);
DISPLAY INVISIBLE (3625 3400);
FORCEPROP 1 LAST MATERIAL X6S
J 2
(3984 3429);
DISPLAY 0.574468 (3984 3429);
PAINT GREEN (3984 3429);
DISPLAY INVISIBLE (3984 3429);
FORCEPROP 2 LAST PACK_TYPE C0201
J 2
(3800 3400);
DISPLAY 0.553191 (3800 3400);
DISPLAY INVISIBLE (3800 3400);
FORCEPROP 2 LAST TOLERANCE 20%
J 2
(3900 3400);
DISPLAY 0.553191 (3900 3400);
DISPLAY INVISIBLE (3900 3400);
FORCEPROP 1 LAST PART_NUMBER SP_CH4221MEE01
J 2
(3859 3438);
DISPLAY 0.574468 (3859 3438);
PAINT GREEN (3859 3438);
DISPLAY INVISIBLE (3859 3438);
FORCEPROP 1 LAST LOCATION C938
J 0
(4225 3425);
DISPLAY 1.021277 (4225 3425);
DISPLAY INVISIBLE (4225 3425);
FORCEPROP 1 LAST PATH I165
J 2
(3975 3350);
DISPLAY 0.723404 (3975 3350);
DISPLAY INVISIBLE (3975 3350);
FORCEADD Q_CAP_DIFFBUS..2
R 2
(3975 3500);
FORCEPROP 1 LAST LOCATION C937
J 2
(4209 3517);
DISPLAY 0.723404 (4209 3517);
PAINT GREEN (4209 3517);
FORCEPROP 2 LAST $SEC 1
J 2
(4150 3575);
DISPLAY 0.680851 (4150 3575);
PAINT MONO (4150 3575);
DISPLAY INVISIBLE (4150 3575);
FORCEPROP 2 LAST CDS_SEC 1
J 2
(4150 3575);
DISPLAY 0.680851 (4150 3575);
DISPLAY INVISIBLE (4150 3575);
FORCEPROP 2 LASTPIN (4050 3500) $PN 1
J 0
(4060 3510);
DISPLAY 0.808511 (4060 3510);
FORCEPROP 2 LASTPIN (3900 3500) $PN 2
J 2
(3890 3510);
DISPLAY 0.808511 (3890 3510);
FORCEPROP 2 LAST VALUE DIFF BUS_0.22UF
J 2
(3825 3500);
DISPLAY 0.553191 (3825 3500);
FORCEPROP 1 LAST CDS_LMAN_SYM_OUTLINE -25,50,25,-50
J 2
(3975 3500);
DISPLAY 0.468085 (3975 3500);
PAINT GREEN (3975 3500);
DISPLAY INVISIBLE (3975 3500);
FORCEPROP 2 LAST CDS_LIB pure_quanta
J 2
(3975 3500);
DISPLAY INVISIBLE (3975 3500);
FORCEPROP 1 LAST PIN_NAMES_ROTATE TRUE
J 2
(3975 3500);
DISPLAY 0.489362 (3975 3500);
PAINT GREEN (3975 3500);
DISPLAY INVISIBLE (3975 3500);
FORCEPROP 2 LAST VOLTAGE 6.3V
J 2
(3625 3550);
DISPLAY 0.553191 (3625 3550);
DISPLAY INVISIBLE (3625 3550);
FORCEPROP 1 LAST MATERIAL X6S
J 2
(3984 3579);
DISPLAY 0.574468 (3984 3579);
PAINT GREEN (3984 3579);
DISPLAY INVISIBLE (3984 3579);
FORCEPROP 2 LAST PACK_TYPE C0201
J 2
(3800 3550);
DISPLAY 0.553191 (3800 3550);
DISPLAY INVISIBLE (3800 3550);
FORCEPROP 2 LAST TOLERANCE 20%
J 2
(3900 3550);
DISPLAY 0.553191 (3900 3550);
DISPLAY INVISIBLE (3900 3550);
FORCEPROP 1 LAST PART_NUMBER SP_CH4221MEE01
J 2
(3859 3588);
DISPLAY 0.574468 (3859 3588);
PAINT GREEN (3859 3588);
DISPLAY INVISIBLE (3859 3588);
FORCEPROP 1 LAST LOCATION C937
J 0
(4225 3575);
DISPLAY 1.021277 (4225 3575);
DISPLAY INVISIBLE (4225 3575);
FORCEPROP 1 LAST PATH I166
J 2
(3975 3500);
DISPLAY 0.723404 (3975 3500);
DISPLAY INVISIBLE (3975 3500);
FORCEADD Q_CAP_DIFFBUS..2
R 2
(3975 3550);
FORCEPROP 1 LAST LOCATION C936
J 2
(4209 3567);
DISPLAY 0.723404 (4209 3567);
PAINT GREEN (4209 3567);
FORCEPROP 2 LAST $SEC 1
J 2
(4150 3625);
DISPLAY 0.680851 (4150 3625);
PAINT MONO (4150 3625);
DISPLAY INVISIBLE (4150 3625);
FORCEPROP 2 LAST CDS_SEC 1
J 2
(4150 3625);
DISPLAY 0.680851 (4150 3625);
DISPLAY INVISIBLE (4150 3625);
FORCEPROP 2 LASTPIN (4050 3550) $PN 1
J 0
(4060 3560);
DISPLAY 0.808511 (4060 3560);
FORCEPROP 2 LASTPIN (3900 3550) $PN 2
J 2
(3890 3560);
DISPLAY 0.808511 (3890 3560);
FORCEPROP 2 LAST VALUE DIFF BUS_0.22UF
J 2
(3825 3550);
DISPLAY 0.553191 (3825 3550);
FORCEPROP 1 LAST CDS_LMAN_SYM_OUTLINE -25,50,25,-50
J 2
(3975 3550);
DISPLAY 0.468085 (3975 3550);
PAINT GREEN (3975 3550);
DISPLAY INVISIBLE (3975 3550);
FORCEPROP 2 LAST CDS_LIB pure_quanta
J 2
(3975 3550);
DISPLAY INVISIBLE (3975 3550);
FORCEPROP 1 LAST PIN_NAMES_ROTATE TRUE
J 2
(3975 3550);
DISPLAY 0.489362 (3975 3550);
PAINT GREEN (3975 3550);
DISPLAY INVISIBLE (3975 3550);
FORCEPROP 2 LAST VOLTAGE 6.3V
J 2
(3625 3600);
DISPLAY 0.553191 (3625 3600);
DISPLAY INVISIBLE (3625 3600);
FORCEPROP 1 LAST MATERIAL X6S
J 2
(3984 3629);
DISPLAY 0.574468 (3984 3629);
PAINT GREEN (3984 3629);
DISPLAY INVISIBLE (3984 3629);
FORCEPROP 2 LAST PACK_TYPE C0201
J 2
(3800 3600);
DISPLAY 0.553191 (3800 3600);
DISPLAY INVISIBLE (3800 3600);
FORCEPROP 2 LAST TOLERANCE 20%
J 2
(3900 3600);
DISPLAY 0.553191 (3900 3600);
DISPLAY INVISIBLE (3900 3600);
FORCEPROP 1 LAST PART_NUMBER SP_CH4221MEE01
J 2
(3859 3638);
DISPLAY 0.574468 (3859 3638);
PAINT GREEN (3859 3638);
DISPLAY INVISIBLE (3859 3638);
FORCEPROP 1 LAST LOCATION C936
J 0
(4225 3625);
DISPLAY 1.021277 (4225 3625);
DISPLAY INVISIBLE (4225 3625);
FORCEPROP 1 LAST PATH I167
J 2
(3975 3550);
DISPLAY 0.723404 (3975 3550);
DISPLAY INVISIBLE (3975 3550);
FORCEADD Q_CAP_DIFFBUS..2
R 2
(3975 3700);
FORCEPROP 1 LAST LOCATION C935
J 2
(4209 3717);
DISPLAY 0.723404 (4209 3717);
PAINT GREEN (4209 3717);
FORCEPROP 2 LAST $SEC 1
J 2
(4150 3775);
DISPLAY 0.680851 (4150 3775);
PAINT MONO (4150 3775);
DISPLAY INVISIBLE (4150 3775);
FORCEPROP 2 LAST CDS_SEC 1
J 2
(4150 3775);
DISPLAY 0.680851 (4150 3775);
DISPLAY INVISIBLE (4150 3775);
FORCEPROP 2 LASTPIN (4050 3700) $PN 1
J 0
(4060 3710);
DISPLAY 0.808511 (4060 3710);
FORCEPROP 2 LASTPIN (3900 3700) $PN 2
J 2
(3890 3710);
DISPLAY 0.808511 (3890 3710);
FORCEPROP 2 LAST VALUE DIFF BUS_0.22UF
J 2
(3825 3700);
DISPLAY 0.553191 (3825 3700);
FORCEPROP 1 LAST CDS_LMAN_SYM_OUTLINE -25,50,25,-50
J 2
(3975 3700);
DISPLAY 0.468085 (3975 3700);
PAINT GREEN (3975 3700);
DISPLAY INVISIBLE (3975 3700);
FORCEPROP 2 LAST CDS_LIB pure_quanta
J 2
(3975 3700);
DISPLAY INVISIBLE (3975 3700);
FORCEPROP 1 LAST PIN_NAMES_ROTATE TRUE
J 2
(3975 3700);
DISPLAY 0.489362 (3975 3700);
PAINT GREEN (3975 3700);
DISPLAY INVISIBLE (3975 3700);
FORCEPROP 2 LAST VOLTAGE 6.3V
J 2
(3625 3750);
DISPLAY 0.553191 (3625 3750);
DISPLAY INVISIBLE (3625 3750);
FORCEPROP 1 LAST MATERIAL X6S
J 2
(3984 3779);
DISPLAY 0.574468 (3984 3779);
PAINT GREEN (3984 3779);
DISPLAY INVISIBLE (3984 3779);
FORCEPROP 2 LAST PACK_TYPE C0201
J 2
(3800 3750);
DISPLAY 0.553191 (3800 3750);
DISPLAY INVISIBLE (3800 3750);
FORCEPROP 2 LAST TOLERANCE 20%
J 2
(3900 3750);
DISPLAY 0.553191 (3900 3750);
DISPLAY INVISIBLE (3900 3750);
FORCEPROP 1 LAST PART_NUMBER SP_CH4221MEE01
J 2
(3859 3788);
DISPLAY 0.574468 (3859 3788);
PAINT GREEN (3859 3788);
DISPLAY INVISIBLE (3859 3788);
FORCEPROP 1 LAST LOCATION C935
J 0
(4225 3775);
DISPLAY 1.021277 (4225 3775);
DISPLAY INVISIBLE (4225 3775);
FORCEPROP 1 LAST PATH I168
J 2
(3975 3700);
DISPLAY 0.723404 (3975 3700);
DISPLAY INVISIBLE (3975 3700);
FORCEADD Q_CAP_DIFFBUS..2
R 2
(3975 3750);
FORCEPROP 1 LAST LOCATION C934
J 2
(4209 3767);
DISPLAY 0.723404 (4209 3767);
PAINT GREEN (4209 3767);
FORCEPROP 2 LAST $SEC 1
J 2
(4150 3825);
DISPLAY 0.680851 (4150 3825);
PAINT MONO (4150 3825);
DISPLAY INVISIBLE (4150 3825);
FORCEPROP 2 LAST CDS_SEC 1
J 2
(4150 3825);
DISPLAY 0.680851 (4150 3825);
DISPLAY INVISIBLE (4150 3825);
FORCEPROP 2 LASTPIN (4050 3750) $PN 1
J 0
(4060 3760);
DISPLAY 0.808511 (4060 3760);
FORCEPROP 2 LASTPIN (3900 3750) $PN 2
J 2
(3890 3760);
DISPLAY 0.808511 (3890 3760);
FORCEPROP 2 LAST TOLERANCE 20%
J 2
(4075 3900);
DISPLAY 0.553191 (4075 3900);
PAINT GREEN (4075 3900);
FORCEPROP 2 LAST VALUE DIFF BUS_0.22UF
J 2
(3825 3750);
DISPLAY 0.553191 (3825 3750);
FORCEPROP 1 LAST MATERIAL X6S
J 2
(3934 3954);
DISPLAY 0.574468 (3934 3954);
PAINT GREEN (3934 3954);
FORCEPROP 2 LAST VOLTAGE 6.3V
J 2
(4225 3900);
DISPLAY 0.553191 (4225 3900);
PAINT GREEN (4225 3900);
FORCEPROP 2 LAST PACK_TYPE C0201
J 2
(3975 3900);
DISPLAY 0.553191 (3975 3900);
PAINT GREEN (3975 3900);
FORCEPROP 2 LAST CDS_LIB pure_quanta
J 2
(3975 3750);
DISPLAY INVISIBLE (3975 3750);
FORCEPROP 1 LAST CDS_LMAN_SYM_OUTLINE -25,50,25,-50
J 2
(3975 3750);
DISPLAY 0.468085 (3975 3750);
PAINT GREEN (3975 3750);
DISPLAY INVISIBLE (3975 3750);
FORCEPROP 1 LAST PIN_NAMES_ROTATE TRUE
J 2
(3975 3750);
DISPLAY 0.489362 (3975 3750);
PAINT GREEN (3975 3750);
DISPLAY INVISIBLE (3975 3750);
FORCEPROP 1 LAST PART_NUMBER SP_CH4221MEE01
J 2
(4234 3838);
DISPLAY 0.574468 (4234 3838);
PAINT GREEN (4234 3838);
DISPLAY INVISIBLE (4234 3838);
FORCEPROP 1 LAST LOCATION C934
J 0
(4225 3825);
DISPLAY 1.021277 (4225 3825);
DISPLAY INVISIBLE (4225 3825);
FORCEPROP 1 LAST PATH I169
J 2
(3975 3750);
DISPLAY 0.723404 (3975 3750);
DISPLAY INVISIBLE (3975 3750);
FORCEADD TAP..1
R 2
(-1300 1375);
FORCEPROP 3 LASTPIN (-1250 1375) SIG_NAME P5E_CPU0_P0_TX_DN<5>
J 0
(-1240 1385);
DISPLAY 0.659574 (-1240 1385);
PAINT MONO (-1240 1385);
DISPLAY INVISIBLE (-1240 1385);
FORCEPROP 1 LASTPIN (-1250 1375) BN 5
J 2
(-1238 1383);
DISPLAY 0.680851 (-1238 1383);
PAINT GREEN (-1238 1383);
FORCEPROP 2 LAST CDS_LIB standard
J 0
(-1300 1375);
DISPLAY INVISIBLE (-1300 1375);
FORCEPROP 1 LAST BODY_TYPE PLUMBING
J 2
(-1300 1425);
DISPLAY 0.872340 (-1300 1425);
PAINT GREEN (-1300 1425);
DISPLAY INVISIBLE (-1300 1425);
FORCEPROP 1 LAST HDL_TAP TRUE
J 2
(-1625 1250);
DISPLAY 0.872340 (-1625 1250);
DISPLAY INVISIBLE (-1625 1250);
FORCEPROP 1 LAST PATH I17
J 2
(-1298 1375);
DISPLAY 0.872340 (-1298 1375);
PAINT GREEN (-1298 1375);
DISPLAY INVISIBLE (-1298 1375);
FORCEADD TAP..1
(4525 575);
FORCEPROP 3 LASTPIN (4475 575) SIG_NAME P5E_CPU0_P1_TX_C_DN<1>
J 0
(4485 585);
DISPLAY 0.659574 (4485 585);
PAINT MONO (4485 585);
DISPLAY INVISIBLE (4485 585);
FORCEPROP 1 LASTPIN (4475 575) BN 1
J 0
(4463 583);
DISPLAY 0.680851 (4463 583);
PAINT GREEN (4463 583);
FORCEPROP 2 LAST CDS_LIB standard
J 0
(4525 575);
DISPLAY INVISIBLE (4525 575);
FORCEPROP 1 LAST BODY_TYPE PLUMBING
J 0
(4525 625);
DISPLAY 0.872340 (4525 625);
PAINT GREEN (4525 625);
DISPLAY INVISIBLE (4525 625);
FORCEPROP 1 LAST HDL_TAP TRUE
J 0
(4850 450);
DISPLAY 0.872340 (4850 450);
DISPLAY INVISIBLE (4850 450);
FORCEPROP 1 LAST PATH I170
J 0
(4523 575);
DISPLAY 0.872340 (4523 575);
PAINT GREEN (4523 575);
DISPLAY INVISIBLE (4523 575);
FORCEADD TAP..1
(4525 775);
FORCEPROP 3 LASTPIN (4475 775) SIG_NAME P5E_CPU0_P1_TX_C_DN<2>
J 0
(4485 785);
DISPLAY 0.659574 (4485 785);
PAINT MONO (4485 785);
DISPLAY INVISIBLE (4485 785);
FORCEPROP 1 LASTPIN (4475 775) BN 2
J 0
(4463 783);
DISPLAY 0.680851 (4463 783);
PAINT GREEN (4463 783);
FORCEPROP 2 LAST CDS_LIB standard
J 0
(4525 775);
DISPLAY INVISIBLE (4525 775);
FORCEPROP 1 LAST BODY_TYPE PLUMBING
J 0
(4525 825);
DISPLAY 0.872340 (4525 825);
PAINT GREEN (4525 825);
DISPLAY INVISIBLE (4525 825);
FORCEPROP 1 LAST HDL_TAP TRUE
J 0
(4850 650);
DISPLAY 0.872340 (4850 650);
DISPLAY INVISIBLE (4850 650);
FORCEPROP 1 LAST PATH I171
J 0
(4523 775);
DISPLAY 0.872340 (4523 775);
PAINT GREEN (4523 775);
DISPLAY INVISIBLE (4523 775);
FORCEADD TAP..1
(4525 975);
FORCEPROP 3 LASTPIN (4475 975) SIG_NAME P5E_CPU0_P1_TX_C_DN<3>
J 0
(4485 985);
DISPLAY 0.659574 (4485 985);
PAINT MONO (4485 985);
DISPLAY INVISIBLE (4485 985);
FORCEPROP 1 LASTPIN (4475 975) BN 3
J 0
(4463 983);
DISPLAY 0.680851 (4463 983);
PAINT GREEN (4463 983);
FORCEPROP 2 LAST CDS_LIB standard
J 0
(4525 975);
DISPLAY INVISIBLE (4525 975);
FORCEPROP 1 LAST BODY_TYPE PLUMBING
J 0
(4525 1025);
DISPLAY 0.872340 (4525 1025);
PAINT GREEN (4525 1025);
DISPLAY INVISIBLE (4525 1025);
FORCEPROP 1 LAST HDL_TAP TRUE
J 0
(4850 850);
DISPLAY 0.872340 (4850 850);
DISPLAY INVISIBLE (4850 850);
FORCEPROP 1 LAST PATH I172
J 0
(4523 975);
DISPLAY 0.872340 (4523 975);
PAINT GREEN (4523 975);
DISPLAY INVISIBLE (4523 975);
FORCEADD TAP..1
(4725 325);
FORCEPROP 3 LASTPIN (4675 325) SIG_NAME P5E_CPU0_P1_TX_C_DP<0>
J 0
(4685 335);
DISPLAY 0.659574 (4685 335);
PAINT MONO (4685 335);
DISPLAY INVISIBLE (4685 335);
FORCEPROP 1 LASTPIN (4675 325) BN 0
J 0
(4663 333);
DISPLAY 0.680851 (4663 333);
PAINT GREEN (4663 333);
FORCEPROP 2 LAST CDS_LIB standard
J 0
(4725 325);
DISPLAY INVISIBLE (4725 325);
FORCEPROP 1 LAST BODY_TYPE PLUMBING
J 0
(4725 375);
DISPLAY 0.872340 (4725 375);
PAINT GREEN (4725 375);
DISPLAY INVISIBLE (4725 375);
FORCEPROP 1 LAST HDL_TAP TRUE
J 0
(5050 200);
DISPLAY 0.872340 (5050 200);
DISPLAY INVISIBLE (5050 200);
FORCEPROP 1 LAST PATH I173
J 0
(4723 325);
DISPLAY 0.872340 (4723 325);
PAINT GREEN (4723 325);
DISPLAY INVISIBLE (4723 325);
FORCEADD TAP..1
(4725 525);
FORCEPROP 3 LASTPIN (4675 525) SIG_NAME P5E_CPU0_P1_TX_C_DP<1>
J 0
(4685 535);
DISPLAY 0.659574 (4685 535);
PAINT MONO (4685 535);
DISPLAY INVISIBLE (4685 535);
FORCEPROP 1 LASTPIN (4675 525) BN 1
J 0
(4663 533);
DISPLAY 0.680851 (4663 533);
PAINT GREEN (4663 533);
FORCEPROP 2 LAST CDS_LIB standard
J 0
(4725 525);
DISPLAY INVISIBLE (4725 525);
FORCEPROP 1 LAST BODY_TYPE PLUMBING
J 0
(4725 575);
DISPLAY 0.872340 (4725 575);
PAINT GREEN (4725 575);
DISPLAY INVISIBLE (4725 575);
FORCEPROP 1 LAST HDL_TAP TRUE
J 0
(5050 400);
DISPLAY 0.872340 (5050 400);
DISPLAY INVISIBLE (5050 400);
FORCEPROP 1 LAST PATH I174
J 0
(4723 525);
DISPLAY 0.872340 (4723 525);
PAINT GREEN (4723 525);
DISPLAY INVISIBLE (4723 525);
FORCEADD TAP..1
(4725 725);
FORCEPROP 3 LASTPIN (4675 725) SIG_NAME P5E_CPU0_P1_TX_C_DP<2>
J 0
(4685 735);
DISPLAY 0.659574 (4685 735);
PAINT MONO (4685 735);
DISPLAY INVISIBLE (4685 735);
FORCEPROP 1 LASTPIN (4675 725) BN 2
J 0
(4663 733);
DISPLAY 0.680851 (4663 733);
PAINT GREEN (4663 733);
FORCEPROP 2 LAST CDS_LIB standard
J 0
(4725 725);
DISPLAY INVISIBLE (4725 725);
FORCEPROP 1 LAST BODY_TYPE PLUMBING
J 0
(4725 775);
DISPLAY 0.872340 (4725 775);
PAINT GREEN (4725 775);
DISPLAY INVISIBLE (4725 775);
FORCEPROP 1 LAST HDL_TAP TRUE
J 0
(5050 600);
DISPLAY 0.872340 (5050 600);
DISPLAY INVISIBLE (5050 600);
FORCEPROP 1 LAST PATH I175
J 0
(4723 725);
DISPLAY 0.872340 (4723 725);
PAINT GREEN (4723 725);
DISPLAY INVISIBLE (4723 725);
FORCEADD TAP..1
(4725 925);
FORCEPROP 3 LASTPIN (4675 925) SIG_NAME P5E_CPU0_P1_TX_C_DP<3>
J 0
(4685 935);
DISPLAY 0.659574 (4685 935);
PAINT MONO (4685 935);
DISPLAY INVISIBLE (4685 935);
FORCEPROP 1 LASTPIN (4675 925) BN 3
J 0
(4663 933);
DISPLAY 0.680851 (4663 933);
PAINT GREEN (4663 933);
FORCEPROP 2 LAST CDS_LIB standard
J 0
(4725 925);
DISPLAY INVISIBLE (4725 925);
FORCEPROP 1 LAST BODY_TYPE PLUMBING
J 0
(4725 975);
DISPLAY 0.872340 (4725 975);
PAINT GREEN (4725 975);
DISPLAY INVISIBLE (4725 975);
FORCEPROP 1 LAST HDL_TAP TRUE
J 0
(5050 800);
DISPLAY 0.872340 (5050 800);
DISPLAY INVISIBLE (5050 800);
FORCEPROP 1 LAST PATH I176
J 0
(4723 925);
DISPLAY 0.872340 (4723 925);
PAINT GREEN (4723 925);
DISPLAY INVISIBLE (4723 925);
FORCEADD TAP..1
(4725 1125);
FORCEPROP 3 LASTPIN (4675 1125) SIG_NAME P5E_CPU0_P1_TX_C_DP<4>
J 0
(4685 1135);
DISPLAY 0.659574 (4685 1135);
PAINT MONO (4685 1135);
DISPLAY INVISIBLE (4685 1135);
FORCEPROP 1 LASTPIN (4675 1125) BN 4
J 0
(4663 1133);
DISPLAY 0.680851 (4663 1133);
PAINT GREEN (4663 1133);
FORCEPROP 2 LAST CDS_LIB standard
J 0
(4725 1125);
DISPLAY INVISIBLE (4725 1125);
FORCEPROP 1 LAST BODY_TYPE PLUMBING
J 0
(4725 1175);
DISPLAY 0.872340 (4725 1175);
PAINT GREEN (4725 1175);
DISPLAY INVISIBLE (4725 1175);
FORCEPROP 1 LAST HDL_TAP TRUE
J 0
(5050 1000);
DISPLAY 0.872340 (5050 1000);
DISPLAY INVISIBLE (5050 1000);
FORCEPROP 1 LAST PATH I177
J 0
(4723 1125);
DISPLAY 0.872340 (4723 1125);
PAINT GREEN (4723 1125);
DISPLAY INVISIBLE (4723 1125);
FORCEADD TAP..1
(4525 1375);
FORCEPROP 3 LASTPIN (4475 1375) SIG_NAME P5E_CPU0_P1_TX_C_DN<5>
J 0
(4485 1385);
DISPLAY 0.659574 (4485 1385);
PAINT MONO (4485 1385);
DISPLAY INVISIBLE (4485 1385);
FORCEPROP 1 LASTPIN (4475 1375) BN 5
J 0
(4463 1383);
DISPLAY 0.680851 (4463 1383);
PAINT GREEN (4463 1383);
FORCEPROP 2 LAST CDS_LIB standard
J 0
(4525 1375);
DISPLAY INVISIBLE (4525 1375);
FORCEPROP 1 LAST BODY_TYPE PLUMBING
J 0
(4525 1425);
DISPLAY 0.872340 (4525 1425);
PAINT GREEN (4525 1425);
DISPLAY INVISIBLE (4525 1425);
FORCEPROP 1 LAST HDL_TAP TRUE
J 0
(4850 1250);
DISPLAY 0.872340 (4850 1250);
DISPLAY INVISIBLE (4850 1250);
FORCEPROP 1 LAST PATH I178
J 0
(4523 1375);
DISPLAY 0.872340 (4523 1375);
PAINT GREEN (4523 1375);
DISPLAY INVISIBLE (4523 1375);
FORCEADD TAP..1
(4525 1175);
FORCEPROP 3 LASTPIN (4475 1175) SIG_NAME P5E_CPU0_P1_TX_C_DN<4>
J 0
(4485 1185);
DISPLAY 0.659574 (4485 1185);
PAINT MONO (4485 1185);
DISPLAY INVISIBLE (4485 1185);
FORCEPROP 1 LASTPIN (4475 1175) BN 4
J 0
(4463 1183);
DISPLAY 0.680851 (4463 1183);
PAINT GREEN (4463 1183);
FORCEPROP 2 LAST CDS_LIB standard
J 0
(4525 1175);
DISPLAY INVISIBLE (4525 1175);
FORCEPROP 1 LAST BODY_TYPE PLUMBING
J 0
(4525 1225);
DISPLAY 0.872340 (4525 1225);
PAINT GREEN (4525 1225);
DISPLAY INVISIBLE (4525 1225);
FORCEPROP 1 LAST HDL_TAP TRUE
J 0
(4850 1050);
DISPLAY 0.872340 (4850 1050);
DISPLAY INVISIBLE (4850 1050);
FORCEPROP 1 LAST PATH I179
J 0
(4523 1175);
DISPLAY 0.872340 (4523 1175);
PAINT GREEN (4523 1175);
DISPLAY INVISIBLE (4523 1175);
FORCEADD TAP..1
R 2
(-1300 1575);
FORCEPROP 3 LASTPIN (-1250 1575) SIG_NAME P5E_CPU0_P0_TX_DN<6>
J 0
(-1240 1585);
DISPLAY 0.659574 (-1240 1585);
PAINT MONO (-1240 1585);
DISPLAY INVISIBLE (-1240 1585);
FORCEPROP 1 LASTPIN (-1250 1575) BN 6
J 2
(-1238 1583);
DISPLAY 0.680851 (-1238 1583);
PAINT GREEN (-1238 1583);
FORCEPROP 2 LAST CDS_LIB standard
J 0
(-1300 1575);
DISPLAY INVISIBLE (-1300 1575);
FORCEPROP 1 LAST BODY_TYPE PLUMBING
J 2
(-1300 1625);
DISPLAY 0.872340 (-1300 1625);
PAINT GREEN (-1300 1625);
DISPLAY INVISIBLE (-1300 1625);
FORCEPROP 1 LAST HDL_TAP TRUE
J 2
(-1625 1450);
DISPLAY 0.872340 (-1625 1450);
DISPLAY INVISIBLE (-1625 1450);
FORCEPROP 1 LAST PATH I18
J 2
(-1298 1575);
DISPLAY 0.872340 (-1298 1575);
PAINT GREEN (-1298 1575);
DISPLAY INVISIBLE (-1298 1575);
FORCEADD TAP..1
(4525 1575);
FORCEPROP 3 LASTPIN (4475 1575) SIG_NAME P5E_CPU0_P1_TX_C_DN<6>
J 0
(4485 1585);
DISPLAY 0.659574 (4485 1585);
PAINT MONO (4485 1585);
DISPLAY INVISIBLE (4485 1585);
FORCEPROP 1 LASTPIN (4475 1575) BN 6
J 0
(4463 1583);
DISPLAY 0.680851 (4463 1583);
PAINT GREEN (4463 1583);
FORCEPROP 2 LAST CDS_LIB standard
J 0
(4525 1575);
DISPLAY INVISIBLE (4525 1575);
FORCEPROP 1 LAST BODY_TYPE PLUMBING
J 0
(4525 1625);
DISPLAY 0.872340 (4525 1625);
PAINT GREEN (4525 1625);
DISPLAY INVISIBLE (4525 1625);
FORCEPROP 1 LAST HDL_TAP TRUE
J 0
(4850 1450);
DISPLAY 0.872340 (4850 1450);
DISPLAY INVISIBLE (4850 1450);
FORCEPROP 1 LAST PATH I180
J 0
(4523 1575);
DISPLAY 0.872340 (4523 1575);
PAINT GREEN (4523 1575);
DISPLAY INVISIBLE (4523 1575);
FORCEADD TAP..1
(4525 1775);
FORCEPROP 3 LASTPIN (4475 1775) SIG_NAME P5E_CPU0_P1_TX_C_DN<7>
J 0
(4485 1785);
DISPLAY 0.659574 (4485 1785);
PAINT MONO (4485 1785);
DISPLAY INVISIBLE (4485 1785);
FORCEPROP 1 LASTPIN (4475 1775) BN 7
J 0
(4463 1783);
DISPLAY 0.680851 (4463 1783);
PAINT GREEN (4463 1783);
FORCEPROP 2 LAST CDS_LIB standard
J 0
(4525 1775);
DISPLAY INVISIBLE (4525 1775);
FORCEPROP 1 LAST BODY_TYPE PLUMBING
J 0
(4525 1825);
DISPLAY 0.872340 (4525 1825);
PAINT GREEN (4525 1825);
DISPLAY INVISIBLE (4525 1825);
FORCEPROP 1 LAST HDL_TAP TRUE
J 0
(4850 1650);
DISPLAY 0.872340 (4850 1650);
DISPLAY INVISIBLE (4850 1650);
FORCEPROP 1 LAST PATH I181
J 0
(4523 1775);
DISPLAY 0.872340 (4523 1775);
PAINT GREEN (4523 1775);
DISPLAY INVISIBLE (4523 1775);
FORCEADD TAP..1
(4725 1325);
FORCEPROP 3 LASTPIN (4675 1325) SIG_NAME P5E_CPU0_P1_TX_C_DP<5>
J 0
(4685 1335);
DISPLAY 0.659574 (4685 1335);
PAINT MONO (4685 1335);
DISPLAY INVISIBLE (4685 1335);
FORCEPROP 1 LASTPIN (4675 1325) BN 5
J 0
(4663 1333);
DISPLAY 0.680851 (4663 1333);
PAINT GREEN (4663 1333);
FORCEPROP 2 LAST CDS_LIB standard
J 0
(4725 1325);
DISPLAY INVISIBLE (4725 1325);
FORCEPROP 1 LAST BODY_TYPE PLUMBING
J 0
(4725 1375);
DISPLAY 0.872340 (4725 1375);
PAINT GREEN (4725 1375);
DISPLAY INVISIBLE (4725 1375);
FORCEPROP 1 LAST HDL_TAP TRUE
J 0
(5050 1200);
DISPLAY 0.872340 (5050 1200);
DISPLAY INVISIBLE (5050 1200);
FORCEPROP 1 LAST PATH I182
J 0
(4723 1325);
DISPLAY 0.872340 (4723 1325);
PAINT GREEN (4723 1325);
DISPLAY INVISIBLE (4723 1325);
FORCEADD TAP..1
(4725 1525);
FORCEPROP 3 LASTPIN (4675 1525) SIG_NAME P5E_CPU0_P1_TX_C_DP<6>
J 0
(4685 1535);
DISPLAY 0.659574 (4685 1535);
PAINT MONO (4685 1535);
DISPLAY INVISIBLE (4685 1535);
FORCEPROP 1 LASTPIN (4675 1525) BN 6
J 0
(4663 1533);
DISPLAY 0.680851 (4663 1533);
PAINT GREEN (4663 1533);
FORCEPROP 2 LAST CDS_LIB standard
J 0
(4725 1525);
DISPLAY INVISIBLE (4725 1525);
FORCEPROP 1 LAST BODY_TYPE PLUMBING
J 0
(4725 1575);
DISPLAY 0.872340 (4725 1575);
PAINT GREEN (4725 1575);
DISPLAY INVISIBLE (4725 1575);
FORCEPROP 1 LAST HDL_TAP TRUE
J 0
(5050 1400);
DISPLAY 0.872340 (5050 1400);
DISPLAY INVISIBLE (5050 1400);
FORCEPROP 1 LAST PATH I183
J 0
(4723 1525);
DISPLAY 0.872340 (4723 1525);
PAINT GREEN (4723 1525);
DISPLAY INVISIBLE (4723 1525);
FORCEADD TAP..1
(4725 1725);
FORCEPROP 3 LASTPIN (4675 1725) SIG_NAME P5E_CPU0_P1_TX_C_DP<7>
J 0
(4685 1735);
DISPLAY 0.659574 (4685 1735);
PAINT MONO (4685 1735);
DISPLAY INVISIBLE (4685 1735);
FORCEPROP 1 LASTPIN (4675 1725) BN 7
J 0
(4663 1733);
DISPLAY 0.680851 (4663 1733);
PAINT GREEN (4663 1733);
FORCEPROP 2 LAST CDS_LIB standard
J 0
(4725 1725);
DISPLAY INVISIBLE (4725 1725);
FORCEPROP 1 LAST BODY_TYPE PLUMBING
J 0
(4725 1775);
DISPLAY 0.872340 (4725 1775);
PAINT GREEN (4725 1775);
DISPLAY INVISIBLE (4725 1775);
FORCEPROP 1 LAST HDL_TAP TRUE
J 0
(5050 1600);
DISPLAY 0.872340 (5050 1600);
DISPLAY INVISIBLE (5050 1600);
FORCEPROP 1 LAST PATH I184
J 0
(4723 1725);
DISPLAY 0.872340 (4723 1725);
PAINT GREEN (4723 1725);
DISPLAY INVISIBLE (4723 1725);
FORCEADD OFFPAGE..2
(5725 1800);
FORCEPROP 2 LAST $XR0 284 
J 0
(5914 1800);
DISPLAY 0.638298 (5914 1800);
PAINT MONO (5914 1800);
FORCEPROP 2 LAST CDS_LIB standard
J 0
(5725 1800);
DISPLAY INVISIBLE (5725 1800);
FORCEPROP 1 LAST OFFPAGE TRUE
J 0
(6050 1675);
DISPLAY 0.872340 (6050 1675);
DISPLAY INVISIBLE (6050 1675);
FORCEPROP 1 LAST COMMENT_BODY TRUE
J 0
(5680 1705);
DISPLAY 0.872340 (5680 1705);
PAINT GREEN (5680 1705);
DISPLAY INVISIBLE (5680 1705);
FORCEPROP 2 LAST PATH I185
J 0
(5925 1850);
DISPLAY 1.021277 (5925 1850);
DISPLAY INVISIBLE (5925 1850);
FORCEADD OFFPAGE..2
(5725 1750);
FORCEPROP 2 LAST $XR0 284 
J 0
(5914 1750);
DISPLAY 0.638298 (5914 1750);
PAINT MONO (5914 1750);
FORCEPROP 2 LAST CDS_LIB standard
J 0
(5725 1750);
DISPLAY INVISIBLE (5725 1750);
FORCEPROP 1 LAST OFFPAGE TRUE
J 0
(6050 1625);
DISPLAY 0.872340 (6050 1625);
DISPLAY INVISIBLE (6050 1625);
FORCEPROP 1 LAST COMMENT_BODY TRUE
J 0
(5680 1655);
DISPLAY 0.872340 (5680 1655);
PAINT GREEN (5680 1655);
DISPLAY INVISIBLE (5680 1655);
FORCEPROP 2 LAST PATH I186
J 0
(5925 1800);
DISPLAY 1.021277 (5925 1800);
DISPLAY INVISIBLE (5925 1800);
FORCEADD TAP..1
(4525 2350);
FORCEPROP 3 LASTPIN (4475 2350) SIG_NAME P5E_CPU0_P1_TX_C_DN<8>
J 0
(4485 2360);
DISPLAY 0.659574 (4485 2360);
PAINT MONO (4485 2360);
DISPLAY INVISIBLE (4485 2360);
FORCEPROP 1 LASTPIN (4475 2350) BN 8
J 0
(4463 2358);
DISPLAY 0.680851 (4463 2358);
PAINT GREEN (4463 2358);
FORCEPROP 2 LAST CDS_LIB standard
J 0
(4525 2350);
DISPLAY INVISIBLE (4525 2350);
FORCEPROP 1 LAST BODY_TYPE PLUMBING
J 0
(4525 2400);
DISPLAY 0.872340 (4525 2400);
PAINT GREEN (4525 2400);
DISPLAY INVISIBLE (4525 2400);
FORCEPROP 1 LAST HDL_TAP TRUE
J 0
(4850 2225);
DISPLAY 0.872340 (4850 2225);
DISPLAY INVISIBLE (4850 2225);
FORCEPROP 1 LAST PATH I187
J 0
(4523 2350);
DISPLAY 0.872340 (4523 2350);
PAINT GREEN (4523 2350);
DISPLAY INVISIBLE (4523 2350);
FORCEADD TAP..1
(4525 2550);
FORCEPROP 3 LASTPIN (4475 2550) SIG_NAME P5E_CPU0_P1_TX_C_DN<9>
J 0
(4485 2560);
DISPLAY 0.659574 (4485 2560);
PAINT MONO (4485 2560);
DISPLAY INVISIBLE (4485 2560);
FORCEPROP 1 LASTPIN (4475 2550) BN 9
J 0
(4463 2558);
DISPLAY 0.680851 (4463 2558);
PAINT GREEN (4463 2558);
FORCEPROP 2 LAST CDS_LIB standard
J 0
(4525 2550);
DISPLAY INVISIBLE (4525 2550);
FORCEPROP 1 LAST BODY_TYPE PLUMBING
J 0
(4525 2600);
DISPLAY 0.872340 (4525 2600);
PAINT GREEN (4525 2600);
DISPLAY INVISIBLE (4525 2600);
FORCEPROP 1 LAST HDL_TAP TRUE
J 0
(4850 2425);
DISPLAY 0.872340 (4850 2425);
DISPLAY INVISIBLE (4850 2425);
FORCEPROP 1 LAST PATH I188
J 0
(4523 2550);
DISPLAY 0.872340 (4523 2550);
PAINT GREEN (4523 2550);
DISPLAY INVISIBLE (4523 2550);
FORCEADD TAP..1
(4525 2750);
FORCEPROP 3 LASTPIN (4475 2750) SIG_NAME P5E_CPU0_P1_TX_C_DN<10>
J 0
(4485 2760);
DISPLAY 0.659574 (4485 2760);
PAINT MONO (4485 2760);
DISPLAY INVISIBLE (4485 2760);
FORCEPROP 1 LASTPIN (4475 2750) BN 10
J 0
(4463 2758);
DISPLAY 0.680851 (4463 2758);
PAINT GREEN (4463 2758);
FORCEPROP 2 LAST CDS_LIB standard
J 0
(4525 2750);
DISPLAY INVISIBLE (4525 2750);
FORCEPROP 1 LAST BODY_TYPE PLUMBING
J 0
(4525 2800);
DISPLAY 0.872340 (4525 2800);
PAINT GREEN (4525 2800);
DISPLAY INVISIBLE (4525 2800);
FORCEPROP 1 LAST HDL_TAP TRUE
J 0
(4850 2625);
DISPLAY 0.872340 (4850 2625);
DISPLAY INVISIBLE (4850 2625);
FORCEPROP 1 LAST PATH I189
J 0
(4523 2750);
DISPLAY 0.872340 (4523 2750);
PAINT GREEN (4523 2750);
DISPLAY INVISIBLE (4523 2750);
FORCEADD TAP..1
R 2
(-1550 1725);
FORCEPROP 3 LASTPIN (-1500 1725) SIG_NAME P5E_CPU0_P0_TX_DP<7>
J 0
(-1490 1735);
DISPLAY 0.659574 (-1490 1735);
PAINT MONO (-1490 1735);
DISPLAY INVISIBLE (-1490 1735);
FORCEPROP 1 LASTPIN (-1500 1725) BN 7
J 2
(-1488 1733);
DISPLAY 0.680851 (-1488 1733);
PAINT GREEN (-1488 1733);
FORCEPROP 2 LAST CDS_LIB standard
J 0
(-1550 1725);
DISPLAY INVISIBLE (-1550 1725);
FORCEPROP 1 LAST BODY_TYPE PLUMBING
J 2
(-1550 1775);
DISPLAY 0.872340 (-1550 1775);
PAINT GREEN (-1550 1775);
DISPLAY INVISIBLE (-1550 1775);
FORCEPROP 1 LAST HDL_TAP TRUE
J 2
(-1875 1600);
DISPLAY 0.872340 (-1875 1600);
DISPLAY INVISIBLE (-1875 1600);
FORCEPROP 1 LAST PATH I19
J 2
(-1548 1725);
DISPLAY 0.872340 (-1548 1725);
PAINT GREEN (-1548 1725);
DISPLAY INVISIBLE (-1548 1725);
FORCEADD TAP..1
(4525 2950);
FORCEPROP 3 LASTPIN (4475 2950) SIG_NAME P5E_CPU0_P1_TX_C_DN<11>
J 0
(4485 2960);
DISPLAY 0.659574 (4485 2960);
PAINT MONO (4485 2960);
DISPLAY INVISIBLE (4485 2960);
FORCEPROP 1 LASTPIN (4475 2950) BN 11
J 0
(4463 2958);
DISPLAY 0.680851 (4463 2958);
PAINT GREEN (4463 2958);
FORCEPROP 2 LAST CDS_LIB standard
J 0
(4525 2950);
DISPLAY INVISIBLE (4525 2950);
FORCEPROP 1 LAST BODY_TYPE PLUMBING
J 0
(4525 3000);
DISPLAY 0.872340 (4525 3000);
PAINT GREEN (4525 3000);
DISPLAY INVISIBLE (4525 3000);
FORCEPROP 1 LAST HDL_TAP TRUE
J 0
(4850 2825);
DISPLAY 0.872340 (4850 2825);
DISPLAY INVISIBLE (4850 2825);
FORCEPROP 1 LAST PATH I190
J 0
(4523 2950);
DISPLAY 0.872340 (4523 2950);
PAINT GREEN (4523 2950);
DISPLAY INVISIBLE (4523 2950);
FORCEADD TAP..1
(4525 3150);
FORCEPROP 3 LASTPIN (4475 3150) SIG_NAME P5E_CPU0_P1_TX_C_DN<12>
J 0
(4485 3160);
DISPLAY 0.659574 (4485 3160);
PAINT MONO (4485 3160);
DISPLAY INVISIBLE (4485 3160);
FORCEPROP 1 LASTPIN (4475 3150) BN 12
J 0
(4463 3158);
DISPLAY 0.680851 (4463 3158);
PAINT GREEN (4463 3158);
FORCEPROP 2 LAST CDS_LIB standard
J 0
(4525 3150);
DISPLAY INVISIBLE (4525 3150);
FORCEPROP 1 LAST BODY_TYPE PLUMBING
J 0
(4525 3200);
DISPLAY 0.872340 (4525 3200);
PAINT GREEN (4525 3200);
DISPLAY INVISIBLE (4525 3200);
FORCEPROP 1 LAST HDL_TAP TRUE
J 0
(4850 3025);
DISPLAY 0.872340 (4850 3025);
DISPLAY INVISIBLE (4850 3025);
FORCEPROP 1 LAST PATH I191
J 0
(4523 3150);
DISPLAY 0.872340 (4523 3150);
PAINT GREEN (4523 3150);
DISPLAY INVISIBLE (4523 3150);
FORCEADD TAP..1
(4725 2300);
FORCEPROP 3 LASTPIN (4675 2300) SIG_NAME P5E_CPU0_P1_TX_C_DP<8>
J 0
(4685 2310);
DISPLAY 0.659574 (4685 2310);
PAINT MONO (4685 2310);
DISPLAY INVISIBLE (4685 2310);
FORCEPROP 1 LASTPIN (4675 2300) BN 8
J 0
(4663 2308);
DISPLAY 0.680851 (4663 2308);
PAINT GREEN (4663 2308);
FORCEPROP 2 LAST CDS_LIB standard
J 0
(4725 2300);
DISPLAY INVISIBLE (4725 2300);
FORCEPROP 1 LAST BODY_TYPE PLUMBING
J 0
(4725 2350);
DISPLAY 0.872340 (4725 2350);
PAINT GREEN (4725 2350);
DISPLAY INVISIBLE (4725 2350);
FORCEPROP 1 LAST HDL_TAP TRUE
J 0
(5050 2175);
DISPLAY 0.872340 (5050 2175);
DISPLAY INVISIBLE (5050 2175);
FORCEPROP 1 LAST PATH I192
J 0
(4723 2300);
DISPLAY 0.872340 (4723 2300);
PAINT GREEN (4723 2300);
DISPLAY INVISIBLE (4723 2300);
FORCEADD TAP..1
(4725 2500);
FORCEPROP 3 LASTPIN (4675 2500) SIG_NAME P5E_CPU0_P1_TX_C_DP<9>
J 0
(4685 2510);
DISPLAY 0.659574 (4685 2510);
PAINT MONO (4685 2510);
DISPLAY INVISIBLE (4685 2510);
FORCEPROP 1 LASTPIN (4675 2500) BN 9
J 0
(4663 2508);
DISPLAY 0.680851 (4663 2508);
PAINT GREEN (4663 2508);
FORCEPROP 2 LAST CDS_LIB standard
J 0
(4725 2500);
DISPLAY INVISIBLE (4725 2500);
FORCEPROP 1 LAST BODY_TYPE PLUMBING
J 0
(4725 2550);
DISPLAY 0.872340 (4725 2550);
PAINT GREEN (4725 2550);
DISPLAY INVISIBLE (4725 2550);
FORCEPROP 1 LAST HDL_TAP TRUE
J 0
(5050 2375);
DISPLAY 0.872340 (5050 2375);
DISPLAY INVISIBLE (5050 2375);
FORCEPROP 1 LAST PATH I193
J 0
(4723 2500);
DISPLAY 0.872340 (4723 2500);
PAINT GREEN (4723 2500);
DISPLAY INVISIBLE (4723 2500);
FORCEADD TAP..1
(4725 2700);
FORCEPROP 3 LASTPIN (4675 2700) SIG_NAME P5E_CPU0_P1_TX_C_DP<10>
J 0
(4685 2710);
DISPLAY 0.659574 (4685 2710);
PAINT MONO (4685 2710);
DISPLAY INVISIBLE (4685 2710);
FORCEPROP 1 LASTPIN (4675 2700) BN 10
J 0
(4663 2708);
DISPLAY 0.680851 (4663 2708);
PAINT GREEN (4663 2708);
FORCEPROP 2 LAST CDS_LIB standard
J 0
(4725 2700);
DISPLAY INVISIBLE (4725 2700);
FORCEPROP 1 LAST BODY_TYPE PLUMBING
J 0
(4725 2750);
DISPLAY 0.872340 (4725 2750);
PAINT GREEN (4725 2750);
DISPLAY INVISIBLE (4725 2750);
FORCEPROP 1 LAST HDL_TAP TRUE
J 0
(5050 2575);
DISPLAY 0.872340 (5050 2575);
DISPLAY INVISIBLE (5050 2575);
FORCEPROP 1 LAST PATH I194
J 0
(4723 2700);
DISPLAY 0.872340 (4723 2700);
PAINT GREEN (4723 2700);
DISPLAY INVISIBLE (4723 2700);
FORCEADD TAP..1
(4725 2900);
FORCEPROP 3 LASTPIN (4675 2900) SIG_NAME P5E_CPU0_P1_TX_C_DP<11>
J 0
(4685 2910);
DISPLAY 0.659574 (4685 2910);
PAINT MONO (4685 2910);
DISPLAY INVISIBLE (4685 2910);
FORCEPROP 1 LASTPIN (4675 2900) BN 11
J 0
(4663 2908);
DISPLAY 0.680851 (4663 2908);
PAINT GREEN (4663 2908);
FORCEPROP 2 LAST CDS_LIB standard
J 0
(4725 2900);
DISPLAY INVISIBLE (4725 2900);
FORCEPROP 1 LAST BODY_TYPE PLUMBING
J 0
(4725 2950);
DISPLAY 0.872340 (4725 2950);
PAINT GREEN (4725 2950);
DISPLAY INVISIBLE (4725 2950);
FORCEPROP 1 LAST HDL_TAP TRUE
J 0
(5050 2775);
DISPLAY 0.872340 (5050 2775);
DISPLAY INVISIBLE (5050 2775);
FORCEPROP 1 LAST PATH I195
J 0
(4723 2900);
DISPLAY 0.872340 (4723 2900);
PAINT GREEN (4723 2900);
DISPLAY INVISIBLE (4723 2900);
FORCEADD TAP..1
(4725 3100);
FORCEPROP 3 LASTPIN (4675 3100) SIG_NAME P5E_CPU0_P1_TX_C_DP<12>
J 0
(4685 3110);
DISPLAY 0.659574 (4685 3110);
PAINT MONO (4685 3110);
DISPLAY INVISIBLE (4685 3110);
FORCEPROP 1 LASTPIN (4675 3100) BN 12
J 0
(4663 3108);
DISPLAY 0.680851 (4663 3108);
PAINT GREEN (4663 3108);
FORCEPROP 2 LAST CDS_LIB standard
J 0
(4725 3100);
DISPLAY INVISIBLE (4725 3100);
FORCEPROP 1 LAST BODY_TYPE PLUMBING
J 0
(4725 3150);
DISPLAY 0.872340 (4725 3150);
PAINT GREEN (4725 3150);
DISPLAY INVISIBLE (4725 3150);
FORCEPROP 1 LAST HDL_TAP TRUE
J 0
(5050 2975);
DISPLAY 0.872340 (5050 2975);
DISPLAY INVISIBLE (5050 2975);
FORCEPROP 1 LAST PATH I196
J 0
(4723 3100);
DISPLAY 0.872340 (4723 3100);
PAINT GREEN (4723 3100);
DISPLAY INVISIBLE (4723 3100);
FORCEADD TAP..1
(4525 3350);
FORCEPROP 3 LASTPIN (4475 3350) SIG_NAME P5E_CPU0_P1_TX_C_DN<13>
J 0
(4485 3360);
DISPLAY 0.659574 (4485 3360);
PAINT MONO (4485 3360);
DISPLAY INVISIBLE (4485 3360);
FORCEPROP 1 LASTPIN (4475 3350) BN 13
J 0
(4463 3358);
DISPLAY 0.680851 (4463 3358);
PAINT GREEN (4463 3358);
FORCEPROP 2 LAST CDS_LIB standard
J 0
(4525 3350);
DISPLAY INVISIBLE (4525 3350);
FORCEPROP 1 LAST BODY_TYPE PLUMBING
J 0
(4525 3400);
DISPLAY 0.872340 (4525 3400);
PAINT GREEN (4525 3400);
DISPLAY INVISIBLE (4525 3400);
FORCEPROP 1 LAST HDL_TAP TRUE
J 0
(4850 3225);
DISPLAY 0.872340 (4850 3225);
DISPLAY INVISIBLE (4850 3225);
FORCEPROP 1 LAST PATH I197
J 0
(4523 3350);
DISPLAY 0.872340 (4523 3350);
PAINT GREEN (4523 3350);
DISPLAY INVISIBLE (4523 3350);
FORCEADD TAP..1
(4525 3550);
FORCEPROP 3 LASTPIN (4475 3550) SIG_NAME P5E_CPU0_P1_TX_C_DN<14>
J 0
(4485 3560);
DISPLAY 0.659574 (4485 3560);
PAINT MONO (4485 3560);
DISPLAY INVISIBLE (4485 3560);
FORCEPROP 1 LASTPIN (4475 3550) BN 14
J 0
(4463 3558);
DISPLAY 0.680851 (4463 3558);
PAINT GREEN (4463 3558);
FORCEPROP 2 LAST CDS_LIB standard
J 0
(4525 3550);
DISPLAY INVISIBLE (4525 3550);
FORCEPROP 1 LAST BODY_TYPE PLUMBING
J 0
(4525 3600);
DISPLAY 0.872340 (4525 3600);
PAINT GREEN (4525 3600);
DISPLAY INVISIBLE (4525 3600);
FORCEPROP 1 LAST HDL_TAP TRUE
J 0
(4850 3425);
DISPLAY 0.872340 (4850 3425);
DISPLAY INVISIBLE (4850 3425);
FORCEPROP 1 LAST PATH I198
J 0
(4523 3550);
DISPLAY 0.872340 (4523 3550);
PAINT GREEN (4523 3550);
DISPLAY INVISIBLE (4523 3550);
FORCEADD TAP..1
(4525 3750);
FORCEPROP 3 LASTPIN (4475 3750) SIG_NAME P5E_CPU0_P1_TX_C_DN<15>
J 0
(4485 3760);
DISPLAY 0.659574 (4485 3760);
PAINT MONO (4485 3760);
DISPLAY INVISIBLE (4485 3760);
FORCEPROP 1 LASTPIN (4475 3750) BN 15
J 0
(4463 3758);
DISPLAY 0.680851 (4463 3758);
PAINT GREEN (4463 3758);
FORCEPROP 2 LAST CDS_LIB standard
J 0
(4525 3750);
DISPLAY INVISIBLE (4525 3750);
FORCEPROP 1 LAST BODY_TYPE PLUMBING
J 0
(4525 3800);
DISPLAY 0.872340 (4525 3800);
PAINT GREEN (4525 3800);
DISPLAY INVISIBLE (4525 3800);
FORCEPROP 1 LAST HDL_TAP TRUE
J 0
(4850 3625);
DISPLAY 0.872340 (4850 3625);
DISPLAY INVISIBLE (4850 3625);
FORCEPROP 1 LAST PATH I199
J 0
(4523 3750);
DISPLAY 0.872340 (4523 3750);
PAINT GREEN (4523 3750);
DISPLAY INVISIBLE (4523 3750);
FORCEADD OFFPAGE..1
(-2500 1750);
FORCEPROP 2 LAST $XR0 24 
J 0
(-2751 1750);
DISPLAY 0.638298 (-2751 1750);
PAINT MONO (-2751 1750);
FORCEPROP 2 LAST CDS_LIB standard
J 0
(-2500 1750);
DISPLAY INVISIBLE (-2500 1750);
FORCEPROP 1 LAST OFFPAGE TRUE
J 0
(-2175 1625);
DISPLAY 0.872340 (-2175 1625);
DISPLAY INVISIBLE (-2175 1625);
FORCEPROP 1 LAST COMMENT_BODY TRUE
J 0
(-2375 1650);
DISPLAY 0.872340 (-2375 1650);
PAINT GREEN (-2375 1650);
DISPLAY INVISIBLE (-2375 1650);
FORCEPROP 2 LAST PATH I2
J 0
(-2775 1800);
DISPLAY 1.021277 (-2775 1800);
DISPLAY INVISIBLE (-2775 1800);
FORCEADD TAP..1
R 2
(-1300 1775);
FORCEPROP 3 LASTPIN (-1250 1775) SIG_NAME P5E_CPU0_P0_TX_DN<7>
J 0
(-1240 1785);
DISPLAY 0.659574 (-1240 1785);
PAINT MONO (-1240 1785);
DISPLAY INVISIBLE (-1240 1785);
FORCEPROP 1 LASTPIN (-1250 1775) BN 7
J 2
(-1238 1783);
DISPLAY 0.680851 (-1238 1783);
PAINT GREEN (-1238 1783);
FORCEPROP 2 LAST CDS_LIB standard
J 0
(-1300 1775);
DISPLAY INVISIBLE (-1300 1775);
FORCEPROP 1 LAST BODY_TYPE PLUMBING
J 2
(-1300 1825);
DISPLAY 0.872340 (-1300 1825);
PAINT GREEN (-1300 1825);
DISPLAY INVISIBLE (-1300 1825);
FORCEPROP 1 LAST HDL_TAP TRUE
J 2
(-1625 1650);
DISPLAY 0.872340 (-1625 1650);
DISPLAY INVISIBLE (-1625 1650);
FORCEPROP 1 LAST PATH I20
J 2
(-1298 1775);
DISPLAY 0.872340 (-1298 1775);
PAINT GREEN (-1298 1775);
DISPLAY INVISIBLE (-1298 1775);
FORCEADD TAP..1
(4725 3300);
FORCEPROP 3 LASTPIN (4675 3300) SIG_NAME P5E_CPU0_P1_TX_C_DP<13>
J 0
(4685 3310);
DISPLAY 0.659574 (4685 3310);
PAINT MONO (4685 3310);
DISPLAY INVISIBLE (4685 3310);
FORCEPROP 1 LASTPIN (4675 3300) BN 13
J 0
(4663 3308);
DISPLAY 0.680851 (4663 3308);
PAINT GREEN (4663 3308);
FORCEPROP 2 LAST CDS_LIB standard
J 0
(4725 3300);
DISPLAY INVISIBLE (4725 3300);
FORCEPROP 1 LAST BODY_TYPE PLUMBING
J 0
(4725 3350);
DISPLAY 0.872340 (4725 3350);
PAINT GREEN (4725 3350);
DISPLAY INVISIBLE (4725 3350);
FORCEPROP 1 LAST HDL_TAP TRUE
J 0
(5050 3175);
DISPLAY 0.872340 (5050 3175);
DISPLAY INVISIBLE (5050 3175);
FORCEPROP 1 LAST PATH I200
J 0
(4723 3300);
DISPLAY 0.872340 (4723 3300);
PAINT GREEN (4723 3300);
DISPLAY INVISIBLE (4723 3300);
FORCEADD TAP..1
(4725 3500);
FORCEPROP 3 LASTPIN (4675 3500) SIG_NAME P5E_CPU0_P1_TX_C_DP<14>
J 0
(4685 3510);
DISPLAY 0.659574 (4685 3510);
PAINT MONO (4685 3510);
DISPLAY INVISIBLE (4685 3510);
FORCEPROP 1 LASTPIN (4675 3500) BN 14
J 0
(4663 3508);
DISPLAY 0.680851 (4663 3508);
PAINT GREEN (4663 3508);
FORCEPROP 2 LAST CDS_LIB standard
J 0
(4725 3500);
DISPLAY INVISIBLE (4725 3500);
FORCEPROP 1 LAST BODY_TYPE PLUMBING
J 0
(4725 3550);
DISPLAY 0.872340 (4725 3550);
PAINT GREEN (4725 3550);
DISPLAY INVISIBLE (4725 3550);
FORCEPROP 1 LAST HDL_TAP TRUE
J 0
(5050 3375);
DISPLAY 0.872340 (5050 3375);
DISPLAY INVISIBLE (5050 3375);
FORCEPROP 1 LAST PATH I201
J 0
(4723 3500);
DISPLAY 0.872340 (4723 3500);
PAINT GREEN (4723 3500);
DISPLAY INVISIBLE (4723 3500);
FORCEADD TAP..1
(4725 3700);
FORCEPROP 3 LASTPIN (4675 3700) SIG_NAME P5E_CPU0_P1_TX_C_DP<15>
J 0
(4685 3710);
DISPLAY 0.659574 (4685 3710);
PAINT MONO (4685 3710);
DISPLAY INVISIBLE (4685 3710);
FORCEPROP 1 LASTPIN (4675 3700) BN 15
J 0
(4663 3708);
DISPLAY 0.680851 (4663 3708);
PAINT GREEN (4663 3708);
FORCEPROP 2 LAST CDS_LIB standard
J 0
(4725 3700);
DISPLAY INVISIBLE (4725 3700);
FORCEPROP 1 LAST BODY_TYPE PLUMBING
J 0
(4725 3750);
DISPLAY 0.872340 (4725 3750);
PAINT GREEN (4725 3750);
DISPLAY INVISIBLE (4725 3750);
FORCEPROP 1 LAST HDL_TAP TRUE
J 0
(5050 3575);
DISPLAY 0.872340 (5050 3575);
DISPLAY INVISIBLE (5050 3575);
FORCEPROP 1 LAST PATH I202
J 0
(4723 3700);
DISPLAY 0.872340 (4723 3700);
PAINT GREEN (4723 3700);
DISPLAY INVISIBLE (4723 3700);
FORCEADD OFFPAGE..2
(5725 3725);
FORCEPROP 2 LAST $XR0 284 
J 0
(5914 3725);
DISPLAY 0.638298 (5914 3725);
PAINT MONO (5914 3725);
FORCEPROP 2 LAST CDS_LIB standard
J 0
(5725 3725);
DISPLAY INVISIBLE (5725 3725);
FORCEPROP 1 LAST OFFPAGE TRUE
J 0
(6050 3600);
DISPLAY 0.872340 (6050 3600);
DISPLAY INVISIBLE (6050 3600);
FORCEPROP 1 LAST COMMENT_BODY TRUE
J 0
(5680 3630);
DISPLAY 0.872340 (5680 3630);
PAINT GREEN (5680 3630);
DISPLAY INVISIBLE (5680 3630);
FORCEPROP 2 LAST PATH I203
J 0
(5925 3775);
DISPLAY 1.021277 (5925 3775);
DISPLAY INVISIBLE (5925 3775);
FORCEADD OFFPAGE..2
(5725 3775);
FORCEPROP 2 LAST $XR0 284 
J 0
(5914 3775);
DISPLAY 0.638298 (5914 3775);
PAINT MONO (5914 3775);
FORCEPROP 2 LAST CDS_LIB standard
J 0
(5725 3775);
DISPLAY INVISIBLE (5725 3775);
FORCEPROP 1 LAST OFFPAGE TRUE
J 0
(6050 3650);
DISPLAY 0.872340 (6050 3650);
DISPLAY INVISIBLE (6050 3650);
FORCEPROP 1 LAST COMMENT_BODY TRUE
J 0
(5680 3680);
DISPLAY 0.872340 (5680 3680);
PAINT GREEN (5680 3680);
DISPLAY INVISIBLE (5680 3680);
FORCEPROP 2 LAST PATH I204
J 0
(5925 3825);
DISPLAY 1.021277 (5925 3825);
DISPLAY INVISIBLE (5925 3825);
FORCEADD TAP..1
(4525 375);
FORCEPROP 3 LASTPIN (4475 375) SIG_NAME P5E_CPU0_P1_TX_C_DN<0>
J 0
(4485 385);
DISPLAY 0.659574 (4485 385);
PAINT MONO (4485 385);
DISPLAY INVISIBLE (4485 385);
FORCEPROP 1 LASTPIN (4475 375) BN 0
J 0
(4463 383);
DISPLAY 0.680851 (4463 383);
PAINT GREEN (4463 383);
FORCEPROP 2 LAST CDS_LIB standard
J 0
(4525 375);
DISPLAY INVISIBLE (4525 375);
FORCEPROP 1 LAST BODY_TYPE PLUMBING
J 0
(4525 425);
DISPLAY 0.872340 (4525 425);
PAINT GREEN (4525 425);
DISPLAY INVISIBLE (4525 425);
FORCEPROP 1 LAST HDL_TAP TRUE
J 0
(4850 250);
DISPLAY 0.872340 (4850 250);
DISPLAY INVISIBLE (4850 250);
FORCEPROP 1 LAST PATH I205
J 0
(4523 375);
DISPLAY 0.872340 (4523 375);
PAINT GREEN (4523 375);
DISPLAY INVISIBLE (4523 375);
FORCEADD Q_CAP_DIFFBUS..2
R 2
(3975 1125);
FORCEPROP 1 LAST LOCATION C957
J 2
(4209 1142);
DISPLAY 0.723404 (4209 1142);
PAINT GREEN (4209 1142);
FORCEPROP 2 LAST $SEC 1
J 2
(4150 1200);
DISPLAY 0.680851 (4150 1200);
PAINT MONO (4150 1200);
DISPLAY INVISIBLE (4150 1200);
FORCEPROP 2 LAST CDS_SEC 1
J 2
(4150 1200);
DISPLAY 0.680851 (4150 1200);
DISPLAY INVISIBLE (4150 1200);
FORCEPROP 2 LASTPIN (4050 1125) $PN 1
J 0
(4060 1135);
DISPLAY 0.808511 (4060 1135);
FORCEPROP 2 LASTPIN (3900 1125) $PN 2
J 2
(3890 1135);
DISPLAY 0.808511 (3890 1135);
FORCEPROP 2 LAST VALUE DIFF BUS_0.22UF
J 2
(3825 1125);
DISPLAY 0.553191 (3825 1125);
FORCEPROP 1 LAST PIN_NAMES_ROTATE TRUE
J 2
(3975 1125);
DISPLAY 0.489362 (3975 1125);
PAINT GREEN (3975 1125);
DISPLAY INVISIBLE (3975 1125);
FORCEPROP 2 LAST CDS_LIB pure_quanta
J 2
(3975 1125);
DISPLAY INVISIBLE (3975 1125);
FORCEPROP 1 LAST CDS_LMAN_SYM_OUTLINE -25,50,25,-50
J 2
(3975 1125);
DISPLAY 0.468085 (3975 1125);
PAINT GREEN (3975 1125);
DISPLAY INVISIBLE (3975 1125);
FORCEPROP 2 LAST VOLTAGE 6.3V
J 2
(3625 1175);
DISPLAY 0.553191 (3625 1175);
DISPLAY INVISIBLE (3625 1175);
FORCEPROP 1 LAST MATERIAL X6S
J 2
(3984 1204);
DISPLAY 0.574468 (3984 1204);
PAINT GREEN (3984 1204);
DISPLAY INVISIBLE (3984 1204);
FORCEPROP 2 LAST PACK_TYPE C0201
J 2
(3800 1175);
DISPLAY 0.553191 (3800 1175);
DISPLAY INVISIBLE (3800 1175);
FORCEPROP 2 LAST TOLERANCE 20%
J 2
(3900 1175);
DISPLAY 0.553191 (3900 1175);
DISPLAY INVISIBLE (3900 1175);
FORCEPROP 1 LAST PART_NUMBER SP_CH4221MEE01
J 2
(3859 1213);
DISPLAY 0.574468 (3859 1213);
PAINT GREEN (3859 1213);
DISPLAY INVISIBLE (3859 1213);
FORCEPROP 1 LAST LOCATION C957
J 0
(4225 1200);
DISPLAY 1.021277 (4225 1200);
DISPLAY INVISIBLE (4225 1200);
FORCEPROP 1 LAST PATH I206
J 2
(3975 1125);
DISPLAY 0.723404 (3975 1125);
DISPLAY INVISIBLE (3975 1125);
FORCEADD Q_CAP_DIFFBUS..2
R 2
(3975 1175);
FORCEPROP 1 LAST LOCATION C956
J 2
(4209 1192);
DISPLAY 0.723404 (4209 1192);
PAINT GREEN (4209 1192);
FORCEPROP 2 LAST $SEC 1
J 2
(4150 1250);
DISPLAY 0.680851 (4150 1250);
PAINT MONO (4150 1250);
DISPLAY INVISIBLE (4150 1250);
FORCEPROP 2 LAST CDS_SEC 1
J 2
(4150 1250);
DISPLAY 0.680851 (4150 1250);
DISPLAY INVISIBLE (4150 1250);
FORCEPROP 2 LASTPIN (4050 1175) $PN 1
J 0
(4060 1185);
DISPLAY 0.808511 (4060 1185);
FORCEPROP 2 LASTPIN (3900 1175) $PN 2
J 2
(3890 1185);
DISPLAY 0.808511 (3890 1185);
FORCEPROP 2 LAST VALUE DIFF BUS_0.22UF
J 2
(3825 1175);
DISPLAY 0.553191 (3825 1175);
FORCEPROP 1 LAST PIN_NAMES_ROTATE TRUE
J 2
(3975 1175);
DISPLAY 0.489362 (3975 1175);
PAINT GREEN (3975 1175);
DISPLAY INVISIBLE (3975 1175);
FORCEPROP 2 LAST CDS_LIB pure_quanta
J 2
(3975 1175);
DISPLAY INVISIBLE (3975 1175);
FORCEPROP 1 LAST CDS_LMAN_SYM_OUTLINE -25,50,25,-50
J 2
(3975 1175);
DISPLAY 0.468085 (3975 1175);
PAINT GREEN (3975 1175);
DISPLAY INVISIBLE (3975 1175);
FORCEPROP 2 LAST VOLTAGE 6.3V
J 2
(3625 1225);
DISPLAY 0.553191 (3625 1225);
DISPLAY INVISIBLE (3625 1225);
FORCEPROP 1 LAST MATERIAL X6S
J 2
(3984 1254);
DISPLAY 0.574468 (3984 1254);
PAINT GREEN (3984 1254);
DISPLAY INVISIBLE (3984 1254);
FORCEPROP 2 LAST PACK_TYPE C0201
J 2
(3800 1225);
DISPLAY 0.553191 (3800 1225);
DISPLAY INVISIBLE (3800 1225);
FORCEPROP 2 LAST TOLERANCE 20%
J 2
(3900 1225);
DISPLAY 0.553191 (3900 1225);
DISPLAY INVISIBLE (3900 1225);
FORCEPROP 1 LAST PART_NUMBER SP_CH4221MEE01
J 2
(3859 1263);
DISPLAY 0.574468 (3859 1263);
PAINT GREEN (3859 1263);
DISPLAY INVISIBLE (3859 1263);
FORCEPROP 1 LAST LOCATION C956
J 0
(4225 1250);
DISPLAY 1.021277 (4225 1250);
DISPLAY INVISIBLE (4225 1250);
FORCEPROP 1 LAST PATH I207
J 2
(3975 1175);
DISPLAY 0.723404 (3975 1175);
DISPLAY INVISIBLE (3975 1175);
FORCEADD Q_CAP_DIFFBUS..2
R 2
(3975 1325);
FORCEPROP 1 LAST LOCATION C955
J 2
(4209 1342);
DISPLAY 0.723404 (4209 1342);
PAINT GREEN (4209 1342);
FORCEPROP 2 LAST $SEC 1
J 2
(4150 1400);
DISPLAY 0.680851 (4150 1400);
PAINT MONO (4150 1400);
DISPLAY INVISIBLE (4150 1400);
FORCEPROP 2 LAST CDS_SEC 1
J 2
(4150 1400);
DISPLAY 0.680851 (4150 1400);
DISPLAY INVISIBLE (4150 1400);
FORCEPROP 2 LASTPIN (4050 1325) $PN 1
J 0
(4060 1335);
DISPLAY 0.808511 (4060 1335);
FORCEPROP 2 LASTPIN (3900 1325) $PN 2
J 2
(3890 1335);
DISPLAY 0.808511 (3890 1335);
FORCEPROP 2 LAST VALUE DIFF BUS_0.22UF
J 2
(3825 1325);
DISPLAY 0.553191 (3825 1325);
FORCEPROP 1 LAST PIN_NAMES_ROTATE TRUE
J 2
(3975 1325);
DISPLAY 0.489362 (3975 1325);
PAINT GREEN (3975 1325);
DISPLAY INVISIBLE (3975 1325);
FORCEPROP 2 LAST CDS_LIB pure_quanta
J 2
(3975 1325);
DISPLAY INVISIBLE (3975 1325);
FORCEPROP 1 LAST CDS_LMAN_SYM_OUTLINE -25,50,25,-50
J 2
(3975 1325);
DISPLAY 0.468085 (3975 1325);
PAINT GREEN (3975 1325);
DISPLAY INVISIBLE (3975 1325);
FORCEPROP 2 LAST VOLTAGE 6.3V
J 2
(3625 1375);
DISPLAY 0.553191 (3625 1375);
DISPLAY INVISIBLE (3625 1375);
FORCEPROP 1 LAST MATERIAL X6S
J 2
(3984 1404);
DISPLAY 0.574468 (3984 1404);
PAINT GREEN (3984 1404);
DISPLAY INVISIBLE (3984 1404);
FORCEPROP 2 LAST PACK_TYPE C0201
J 2
(3800 1375);
DISPLAY 0.553191 (3800 1375);
DISPLAY INVISIBLE (3800 1375);
FORCEPROP 2 LAST TOLERANCE 20%
J 2
(3900 1375);
DISPLAY 0.553191 (3900 1375);
DISPLAY INVISIBLE (3900 1375);
FORCEPROP 1 LAST PART_NUMBER SP_CH4221MEE01
J 2
(3859 1413);
DISPLAY 0.574468 (3859 1413);
PAINT GREEN (3859 1413);
DISPLAY INVISIBLE (3859 1413);
FORCEPROP 1 LAST LOCATION C955
J 0
(4225 1400);
DISPLAY 1.021277 (4225 1400);
DISPLAY INVISIBLE (4225 1400);
FORCEPROP 1 LAST PATH I208
J 2
(3975 1325);
DISPLAY 0.723404 (3975 1325);
DISPLAY INVISIBLE (3975 1325);
FORCEADD Q_CAP_DIFFBUS..2
R 2
(-575 375);
FORCEPROP 1 LAST LOCATION C932
J 2
(-341 392);
DISPLAY 0.723404 (-341 392);
PAINT GREEN (-341 392);
FORCEPROP 2 LAST $SEC 1
J 2
(-400 450);
DISPLAY 0.680851 (-400 450);
PAINT MONO (-400 450);
DISPLAY INVISIBLE (-400 450);
FORCEPROP 2 LAST CDS_SEC 1
J 2
(-400 450);
DISPLAY 0.680851 (-400 450);
DISPLAY INVISIBLE (-400 450);
FORCEPROP 2 LASTPIN (-500 375) $PN 1
J 0
(-490 385);
DISPLAY 0.808511 (-490 385);
FORCEPROP 2 LASTPIN (-650 375) $PN 2
J 2
(-660 385);
DISPLAY 0.808511 (-660 385);
FORCEPROP 2 LAST VALUE DIFF BUS_0.22UF
J 2
(-725 375);
DISPLAY 0.553191 (-725 375);
FORCEPROP 1 LAST PIN_NAMES_ROTATE TRUE
J 2
(-575 375);
DISPLAY 0.489362 (-575 375);
PAINT GREEN (-575 375);
DISPLAY INVISIBLE (-575 375);
FORCEPROP 2 LAST CDS_LIB pure_quanta
J 2
(-575 375);
DISPLAY INVISIBLE (-575 375);
FORCEPROP 1 LAST CDS_LMAN_SYM_OUTLINE -25,50,25,-50
J 2
(-575 375);
DISPLAY 0.468085 (-575 375);
PAINT GREEN (-575 375);
DISPLAY INVISIBLE (-575 375);
FORCEPROP 2 LAST VOLTAGE 6.3V
J 2
(-925 425);
DISPLAY 0.553191 (-925 425);
DISPLAY INVISIBLE (-925 425);
FORCEPROP 1 LAST MATERIAL X6S
J 2
(-566 454);
DISPLAY 0.574468 (-566 454);
PAINT GREEN (-566 454);
DISPLAY INVISIBLE (-566 454);
FORCEPROP 2 LAST PACK_TYPE C0201
J 2
(-750 425);
DISPLAY 0.553191 (-750 425);
DISPLAY INVISIBLE (-750 425);
FORCEPROP 2 LAST TOLERANCE 20%
J 2
(-650 425);
DISPLAY 0.553191 (-650 425);
DISPLAY INVISIBLE (-650 425);
FORCEPROP 1 LAST PART_NUMBER SP_CH4221MEE01
J 2
(-691 463);
DISPLAY 0.574468 (-691 463);
PAINT GREEN (-691 463);
DISPLAY INVISIBLE (-691 463);
FORCEPROP 1 LAST LOCATION C932
J 0
(-325 450);
DISPLAY 1.021277 (-325 450);
DISPLAY INVISIBLE (-325 450);
FORCEPROP 1 LAST PATH I21
J 2
(-575 375);
DISPLAY 0.723404 (-575 375);
DISPLAY INVISIBLE (-575 375);
FORCEADD Q_CAP_DIFFBUS..2
R 2
(-575 325);
FORCEPROP 1 LAST LOCATION C933
J 2
(-341 342);
DISPLAY 0.723404 (-341 342);
PAINT GREEN (-341 342);
FORCEPROP 2 LAST $SEC 1
J 2
(-400 400);
DISPLAY 0.680851 (-400 400);
PAINT MONO (-400 400);
DISPLAY INVISIBLE (-400 400);
FORCEPROP 2 LAST CDS_SEC 1
J 2
(-400 400);
DISPLAY 0.680851 (-400 400);
DISPLAY INVISIBLE (-400 400);
FORCEPROP 2 LASTPIN (-500 325) $PN 1
J 0
(-490 335);
DISPLAY 0.808511 (-490 335);
FORCEPROP 2 LASTPIN (-650 325) $PN 2
J 2
(-660 335);
DISPLAY 0.808511 (-660 335);
FORCEPROP 2 LAST VALUE DIFF BUS_0.22UF
J 2
(-725 325);
DISPLAY 0.553191 (-725 325);
FORCEPROP 1 LAST PIN_NAMES_ROTATE TRUE
J 2
(-575 325);
DISPLAY 0.489362 (-575 325);
PAINT GREEN (-575 325);
DISPLAY INVISIBLE (-575 325);
FORCEPROP 2 LAST CDS_LIB pure_quanta
J 2
(-575 325);
DISPLAY INVISIBLE (-575 325);
FORCEPROP 1 LAST CDS_LMAN_SYM_OUTLINE -25,50,25,-50
J 2
(-575 325);
DISPLAY 0.468085 (-575 325);
PAINT GREEN (-575 325);
DISPLAY INVISIBLE (-575 325);
FORCEPROP 2 LAST VOLTAGE 6.3V
J 2
(-925 375);
DISPLAY 0.553191 (-925 375);
DISPLAY INVISIBLE (-925 375);
FORCEPROP 1 LAST MATERIAL X6S
J 2
(-566 404);
DISPLAY 0.574468 (-566 404);
PAINT GREEN (-566 404);
DISPLAY INVISIBLE (-566 404);
FORCEPROP 2 LAST PACK_TYPE C0201
J 2
(-750 375);
DISPLAY 0.553191 (-750 375);
DISPLAY INVISIBLE (-750 375);
FORCEPROP 2 LAST TOLERANCE 20%
J 2
(-650 375);
DISPLAY 0.553191 (-650 375);
DISPLAY INVISIBLE (-650 375);
FORCEPROP 1 LAST PART_NUMBER SP_CH4221MEE01
J 2
(-691 413);
DISPLAY 0.574468 (-691 413);
PAINT GREEN (-691 413);
DISPLAY INVISIBLE (-691 413);
FORCEPROP 1 LAST LOCATION C933
J 0
(-325 400);
DISPLAY 1.021277 (-325 400);
DISPLAY INVISIBLE (-325 400);
FORCEPROP 1 LAST PATH I22
J 2
(-575 325);
DISPLAY 0.723404 (-575 325);
DISPLAY INVISIBLE (-575 325);
FORCEADD Q_CAP_DIFFBUS..2
R 2
(-575 525);
FORCEPROP 1 LAST LOCATION C931
J 2
(-341 542);
DISPLAY 0.723404 (-341 542);
PAINT GREEN (-341 542);
FORCEPROP 2 LAST $SEC 1
J 2
(-400 600);
DISPLAY 0.680851 (-400 600);
PAINT MONO (-400 600);
DISPLAY INVISIBLE (-400 600);
FORCEPROP 2 LAST CDS_SEC 1
J 2
(-400 600);
DISPLAY 0.680851 (-400 600);
DISPLAY INVISIBLE (-400 600);
FORCEPROP 2 LASTPIN (-500 525) $PN 1
J 0
(-490 535);
DISPLAY 0.808511 (-490 535);
FORCEPROP 2 LASTPIN (-650 525) $PN 2
J 2
(-660 535);
DISPLAY 0.808511 (-660 535);
FORCEPROP 2 LAST VALUE DIFF BUS_0.22UF
J 2
(-725 525);
DISPLAY 0.553191 (-725 525);
FORCEPROP 1 LAST PIN_NAMES_ROTATE TRUE
J 2
(-575 525);
DISPLAY 0.489362 (-575 525);
PAINT GREEN (-575 525);
DISPLAY INVISIBLE (-575 525);
FORCEPROP 2 LAST CDS_LIB pure_quanta
J 2
(-575 525);
DISPLAY INVISIBLE (-575 525);
FORCEPROP 1 LAST CDS_LMAN_SYM_OUTLINE -25,50,25,-50
J 2
(-575 525);
DISPLAY 0.468085 (-575 525);
PAINT GREEN (-575 525);
DISPLAY INVISIBLE (-575 525);
FORCEPROP 2 LAST VOLTAGE 6.3V
J 2
(-925 575);
DISPLAY 0.553191 (-925 575);
DISPLAY INVISIBLE (-925 575);
FORCEPROP 1 LAST MATERIAL X6S
J 2
(-566 604);
DISPLAY 0.574468 (-566 604);
PAINT GREEN (-566 604);
DISPLAY INVISIBLE (-566 604);
FORCEPROP 2 LAST PACK_TYPE C0201
J 2
(-750 575);
DISPLAY 0.553191 (-750 575);
DISPLAY INVISIBLE (-750 575);
FORCEPROP 2 LAST TOLERANCE 20%
J 2
(-650 575);
DISPLAY 0.553191 (-650 575);
DISPLAY INVISIBLE (-650 575);
FORCEPROP 1 LAST PART_NUMBER SP_CH4221MEE01
J 2
(-691 613);
DISPLAY 0.574468 (-691 613);
PAINT GREEN (-691 613);
DISPLAY INVISIBLE (-691 613);
FORCEPROP 1 LAST LOCATION C931
J 0
(-325 600);
DISPLAY 1.021277 (-325 600);
DISPLAY INVISIBLE (-325 600);
FORCEPROP 1 LAST PATH I23
J 2
(-575 525);
DISPLAY 0.723404 (-575 525);
DISPLAY INVISIBLE (-575 525);
FORCEADD Q_CAP_DIFFBUS..2
R 2
(-575 575);
FORCEPROP 1 LAST LOCATION C930
J 2
(-341 592);
DISPLAY 0.723404 (-341 592);
PAINT GREEN (-341 592);
FORCEPROP 2 LAST $SEC 1
J 2
(-400 650);
DISPLAY 0.680851 (-400 650);
PAINT MONO (-400 650);
DISPLAY INVISIBLE (-400 650);
FORCEPROP 2 LAST CDS_SEC 1
J 2
(-400 650);
DISPLAY 0.680851 (-400 650);
DISPLAY INVISIBLE (-400 650);
FORCEPROP 2 LASTPIN (-500 575) $PN 1
J 0
(-490 585);
DISPLAY 0.808511 (-490 585);
FORCEPROP 2 LASTPIN (-650 575) $PN 2
J 2
(-660 585);
DISPLAY 0.808511 (-660 585);
FORCEPROP 2 LAST VALUE DIFF BUS_0.22UF
J 2
(-725 575);
DISPLAY 0.553191 (-725 575);
FORCEPROP 1 LAST PIN_NAMES_ROTATE TRUE
J 2
(-575 575);
DISPLAY 0.489362 (-575 575);
PAINT GREEN (-575 575);
DISPLAY INVISIBLE (-575 575);
FORCEPROP 1 LAST CDS_LMAN_SYM_OUTLINE -25,50,25,-50
J 2
(-575 575);
DISPLAY 0.468085 (-575 575);
PAINT GREEN (-575 575);
DISPLAY INVISIBLE (-575 575);
FORCEPROP 2 LAST CDS_LIB pure_quanta
J 2
(-575 575);
DISPLAY INVISIBLE (-575 575);
FORCEPROP 2 LAST VOLTAGE 6.3V
J 2
(-925 625);
DISPLAY 0.553191 (-925 625);
DISPLAY INVISIBLE (-925 625);
FORCEPROP 1 LAST MATERIAL X6S
J 2
(-566 654);
DISPLAY 0.574468 (-566 654);
PAINT GREEN (-566 654);
DISPLAY INVISIBLE (-566 654);
FORCEPROP 2 LAST PACK_TYPE C0201
J 2
(-750 625);
DISPLAY 0.553191 (-750 625);
DISPLAY INVISIBLE (-750 625);
FORCEPROP 2 LAST TOLERANCE 20%
J 2
(-650 625);
DISPLAY 0.553191 (-650 625);
DISPLAY INVISIBLE (-650 625);
FORCEPROP 1 LAST PART_NUMBER SP_CH4221MEE01
J 2
(-691 663);
DISPLAY 0.574468 (-691 663);
PAINT GREEN (-691 663);
DISPLAY INVISIBLE (-691 663);
FORCEPROP 1 LAST LOCATION C930
J 0
(-325 650);
DISPLAY 1.021277 (-325 650);
DISPLAY INVISIBLE (-325 650);
FORCEPROP 1 LAST PATH I24
J 2
(-575 575);
DISPLAY 0.723404 (-575 575);
DISPLAY INVISIBLE (-575 575);
FORCEADD Q_CAP_DIFFBUS..2
R 2
(-575 775);
FORCEPROP 1 LAST LOCATION C928
J 2
(-341 792);
DISPLAY 0.723404 (-341 792);
PAINT GREEN (-341 792);
FORCEPROP 2 LAST $SEC 1
J 2
(-400 850);
DISPLAY 0.680851 (-400 850);
PAINT MONO (-400 850);
DISPLAY INVISIBLE (-400 850);
FORCEPROP 2 LAST CDS_SEC 1
J 2
(-400 850);
DISPLAY 0.680851 (-400 850);
DISPLAY INVISIBLE (-400 850);
FORCEPROP 2 LASTPIN (-500 775) $PN 1
J 0
(-490 785);
DISPLAY 0.808511 (-490 785);
FORCEPROP 2 LASTPIN (-650 775) $PN 2
J 2
(-660 785);
DISPLAY 0.808511 (-660 785);
FORCEPROP 2 LAST VALUE DIFF BUS_0.22UF
J 2
(-725 775);
DISPLAY 0.553191 (-725 775);
FORCEPROP 1 LAST PIN_NAMES_ROTATE TRUE
J 2
(-575 775);
DISPLAY 0.489362 (-575 775);
PAINT GREEN (-575 775);
DISPLAY INVISIBLE (-575 775);
FORCEPROP 2 LAST CDS_LIB pure_quanta
J 2
(-575 775);
DISPLAY INVISIBLE (-575 775);
FORCEPROP 1 LAST CDS_LMAN_SYM_OUTLINE -25,50,25,-50
J 2
(-575 775);
DISPLAY 0.468085 (-575 775);
PAINT GREEN (-575 775);
DISPLAY INVISIBLE (-575 775);
FORCEPROP 2 LAST VOLTAGE 6.3V
J 2
(-925 825);
DISPLAY 0.553191 (-925 825);
DISPLAY INVISIBLE (-925 825);
FORCEPROP 1 LAST MATERIAL X6S
J 2
(-566 854);
DISPLAY 0.574468 (-566 854);
PAINT GREEN (-566 854);
DISPLAY INVISIBLE (-566 854);
FORCEPROP 2 LAST PACK_TYPE C0201
J 2
(-750 825);
DISPLAY 0.553191 (-750 825);
DISPLAY INVISIBLE (-750 825);
FORCEPROP 2 LAST TOLERANCE 20%
J 2
(-650 825);
DISPLAY 0.553191 (-650 825);
DISPLAY INVISIBLE (-650 825);
FORCEPROP 1 LAST PART_NUMBER SP_CH4221MEE01
J 2
(-691 863);
DISPLAY 0.574468 (-691 863);
PAINT GREEN (-691 863);
DISPLAY INVISIBLE (-691 863);
FORCEPROP 1 LAST LOCATION C928
J 0
(-325 850);
DISPLAY 1.021277 (-325 850);
DISPLAY INVISIBLE (-325 850);
FORCEPROP 1 LAST PATH I25
J 2
(-575 775);
DISPLAY 0.723404 (-575 775);
DISPLAY INVISIBLE (-575 775);
FORCEADD Q_CAP_DIFFBUS..2
R 2
(-575 725);
FORCEPROP 1 LAST LOCATION C929
J 2
(-341 742);
DISPLAY 0.723404 (-341 742);
PAINT GREEN (-341 742);
FORCEPROP 2 LAST $SEC 1
J 2
(-400 800);
DISPLAY 0.680851 (-400 800);
PAINT MONO (-400 800);
DISPLAY INVISIBLE (-400 800);
FORCEPROP 2 LAST CDS_SEC 1
J 2
(-400 800);
DISPLAY 0.680851 (-400 800);
DISPLAY INVISIBLE (-400 800);
FORCEPROP 2 LASTPIN (-500 725) $PN 1
J 0
(-490 735);
DISPLAY 0.808511 (-490 735);
FORCEPROP 2 LASTPIN (-650 725) $PN 2
J 2
(-660 735);
DISPLAY 0.808511 (-660 735);
FORCEPROP 2 LAST VALUE DIFF BUS_0.22UF
J 2
(-725 725);
DISPLAY 0.553191 (-725 725);
FORCEPROP 1 LAST PIN_NAMES_ROTATE TRUE
J 2
(-575 725);
DISPLAY 0.489362 (-575 725);
PAINT GREEN (-575 725);
DISPLAY INVISIBLE (-575 725);
FORCEPROP 2 LAST CDS_LIB pure_quanta
J 2
(-575 725);
DISPLAY INVISIBLE (-575 725);
FORCEPROP 1 LAST CDS_LMAN_SYM_OUTLINE -25,50,25,-50
J 2
(-575 725);
DISPLAY 0.468085 (-575 725);
PAINT GREEN (-575 725);
DISPLAY INVISIBLE (-575 725);
FORCEPROP 2 LAST VOLTAGE 6.3V
J 2
(-925 775);
DISPLAY 0.553191 (-925 775);
DISPLAY INVISIBLE (-925 775);
FORCEPROP 1 LAST MATERIAL X6S
J 2
(-566 804);
DISPLAY 0.574468 (-566 804);
PAINT GREEN (-566 804);
DISPLAY INVISIBLE (-566 804);
FORCEPROP 2 LAST PACK_TYPE C0201
J 2
(-750 775);
DISPLAY 0.553191 (-750 775);
DISPLAY INVISIBLE (-750 775);
FORCEPROP 2 LAST TOLERANCE 20%
J 2
(-650 775);
DISPLAY 0.553191 (-650 775);
DISPLAY INVISIBLE (-650 775);
FORCEPROP 1 LAST PART_NUMBER SP_CH4221MEE01
J 2
(-691 813);
DISPLAY 0.574468 (-691 813);
PAINT GREEN (-691 813);
DISPLAY INVISIBLE (-691 813);
FORCEPROP 1 LAST LOCATION C929
J 0
(-325 800);
DISPLAY 1.021277 (-325 800);
DISPLAY INVISIBLE (-325 800);
FORCEPROP 1 LAST PATH I26
J 2
(-575 725);
DISPLAY 0.723404 (-575 725);
DISPLAY INVISIBLE (-575 725);
FORCEADD Q_CAP_DIFFBUS..2
R 2
(-575 925);
FORCEPROP 1 LAST LOCATION C927
J 2
(-341 942);
DISPLAY 0.723404 (-341 942);
PAINT GREEN (-341 942);
FORCEPROP 2 LAST $SEC 1
J 2
(-400 1000);
DISPLAY 0.680851 (-400 1000);
PAINT MONO (-400 1000);
DISPLAY INVISIBLE (-400 1000);
FORCEPROP 2 LAST CDS_SEC 1
J 2
(-400 1000);
DISPLAY 0.680851 (-400 1000);
DISPLAY INVISIBLE (-400 1000);
FORCEPROP 2 LASTPIN (-500 925) $PN 1
J 0
(-490 935);
DISPLAY 0.808511 (-490 935);
FORCEPROP 2 LASTPIN (-650 925) $PN 2
J 2
(-660 935);
DISPLAY 0.808511 (-660 935);
FORCEPROP 2 LAST VALUE DIFF BUS_0.22UF
J 2
(-725 925);
DISPLAY 0.553191 (-725 925);
FORCEPROP 1 LAST PIN_NAMES_ROTATE TRUE
J 2
(-575 925);
DISPLAY 0.489362 (-575 925);
PAINT GREEN (-575 925);
DISPLAY INVISIBLE (-575 925);
FORCEPROP 1 LAST CDS_LMAN_SYM_OUTLINE -25,50,25,-50
J 2
(-575 925);
DISPLAY 0.468085 (-575 925);
PAINT GREEN (-575 925);
DISPLAY INVISIBLE (-575 925);
FORCEPROP 2 LAST CDS_LIB pure_quanta
J 2
(-575 925);
DISPLAY INVISIBLE (-575 925);
FORCEPROP 2 LAST VOLTAGE 6.3V
J 2
(-925 975);
DISPLAY 0.553191 (-925 975);
DISPLAY INVISIBLE (-925 975);
FORCEPROP 1 LAST MATERIAL X6S
J 2
(-566 1004);
DISPLAY 0.574468 (-566 1004);
PAINT GREEN (-566 1004);
DISPLAY INVISIBLE (-566 1004);
FORCEPROP 2 LAST PACK_TYPE C0201
J 2
(-750 975);
DISPLAY 0.553191 (-750 975);
DISPLAY INVISIBLE (-750 975);
FORCEPROP 2 LAST TOLERANCE 20%
J 2
(-650 975);
DISPLAY 0.553191 (-650 975);
DISPLAY INVISIBLE (-650 975);
FORCEPROP 1 LAST PART_NUMBER SP_CH4221MEE01
J 2
(-691 1013);
DISPLAY 0.574468 (-691 1013);
PAINT GREEN (-691 1013);
DISPLAY INVISIBLE (-691 1013);
FORCEPROP 1 LAST LOCATION C927
J 0
(-325 1000);
DISPLAY 1.021277 (-325 1000);
DISPLAY INVISIBLE (-325 1000);
FORCEPROP 1 LAST PATH I27
J 2
(-575 925);
DISPLAY 0.723404 (-575 925);
DISPLAY INVISIBLE (-575 925);
FORCEADD Q_CAP_DIFFBUS..2
R 2
(-575 975);
FORCEPROP 1 LAST LOCATION C926
J 2
(-341 992);
DISPLAY 0.723404 (-341 992);
PAINT GREEN (-341 992);
FORCEPROP 2 LAST $SEC 1
J 2
(-400 1050);
DISPLAY 0.680851 (-400 1050);
PAINT MONO (-400 1050);
DISPLAY INVISIBLE (-400 1050);
FORCEPROP 2 LAST CDS_SEC 1
J 2
(-400 1050);
DISPLAY 0.680851 (-400 1050);
DISPLAY INVISIBLE (-400 1050);
FORCEPROP 2 LASTPIN (-500 975) $PN 1
J 0
(-490 985);
DISPLAY 0.808511 (-490 985);
FORCEPROP 2 LASTPIN (-650 975) $PN 2
J 2
(-660 985);
DISPLAY 0.808511 (-660 985);
FORCEPROP 2 LAST VALUE DIFF BUS_0.22UF
J 2
(-725 975);
DISPLAY 0.553191 (-725 975);
FORCEPROP 1 LAST PIN_NAMES_ROTATE TRUE
J 2
(-575 975);
DISPLAY 0.489362 (-575 975);
PAINT GREEN (-575 975);
DISPLAY INVISIBLE (-575 975);
FORCEPROP 1 LAST CDS_LMAN_SYM_OUTLINE -25,50,25,-50
J 2
(-575 975);
DISPLAY 0.468085 (-575 975);
PAINT GREEN (-575 975);
DISPLAY INVISIBLE (-575 975);
FORCEPROP 2 LAST CDS_LIB pure_quanta
J 2
(-575 975);
DISPLAY INVISIBLE (-575 975);
FORCEPROP 2 LAST VOLTAGE 6.3V
J 2
(-925 1025);
DISPLAY 0.553191 (-925 1025);
DISPLAY INVISIBLE (-925 1025);
FORCEPROP 1 LAST MATERIAL X6S
J 2
(-566 1054);
DISPLAY 0.574468 (-566 1054);
PAINT GREEN (-566 1054);
DISPLAY INVISIBLE (-566 1054);
FORCEPROP 2 LAST PACK_TYPE C0201
J 2
(-750 1025);
DISPLAY 0.553191 (-750 1025);
DISPLAY INVISIBLE (-750 1025);
FORCEPROP 2 LAST TOLERANCE 20%
J 2
(-650 1025);
DISPLAY 0.553191 (-650 1025);
DISPLAY INVISIBLE (-650 1025);
FORCEPROP 1 LAST PART_NUMBER SP_CH4221MEE01
J 2
(-691 1063);
DISPLAY 0.574468 (-691 1063);
PAINT GREEN (-691 1063);
DISPLAY INVISIBLE (-691 1063);
FORCEPROP 1 LAST LOCATION C926
J 0
(-325 1050);
DISPLAY 1.021277 (-325 1050);
DISPLAY INVISIBLE (-325 1050);
FORCEPROP 1 LAST PATH I28
J 2
(-575 975);
DISPLAY 0.723404 (-575 975);
DISPLAY INVISIBLE (-575 975);
FORCEADD Q_CAP_DIFFBUS..2
R 2
(-575 1125);
FORCEPROP 1 LAST LOCATION C925
J 2
(-341 1142);
DISPLAY 0.723404 (-341 1142);
PAINT GREEN (-341 1142);
FORCEPROP 2 LAST $SEC 1
J 2
(-400 1200);
DISPLAY 0.680851 (-400 1200);
PAINT MONO (-400 1200);
DISPLAY INVISIBLE (-400 1200);
FORCEPROP 2 LAST CDS_SEC 1
J 2
(-400 1200);
DISPLAY 0.680851 (-400 1200);
DISPLAY INVISIBLE (-400 1200);
FORCEPROP 2 LASTPIN (-500 1125) $PN 1
J 0
(-490 1135);
DISPLAY 0.808511 (-490 1135);
FORCEPROP 2 LASTPIN (-650 1125) $PN 2
J 2
(-660 1135);
DISPLAY 0.808511 (-660 1135);
FORCEPROP 2 LAST VALUE DIFF BUS_0.22UF
J 2
(-725 1125);
DISPLAY 0.553191 (-725 1125);
FORCEPROP 1 LAST PIN_NAMES_ROTATE TRUE
J 2
(-575 1125);
DISPLAY 0.489362 (-575 1125);
PAINT GREEN (-575 1125);
DISPLAY INVISIBLE (-575 1125);
FORCEPROP 2 LAST CDS_LIB pure_quanta
J 2
(-575 1125);
DISPLAY INVISIBLE (-575 1125);
FORCEPROP 1 LAST CDS_LMAN_SYM_OUTLINE -25,50,25,-50
J 2
(-575 1125);
DISPLAY 0.468085 (-575 1125);
PAINT GREEN (-575 1125);
DISPLAY INVISIBLE (-575 1125);
FORCEPROP 2 LAST VOLTAGE 6.3V
J 2
(-925 1175);
DISPLAY 0.553191 (-925 1175);
DISPLAY INVISIBLE (-925 1175);
FORCEPROP 1 LAST MATERIAL X6S
J 2
(-566 1204);
DISPLAY 0.574468 (-566 1204);
PAINT GREEN (-566 1204);
DISPLAY INVISIBLE (-566 1204);
FORCEPROP 2 LAST PACK_TYPE C0201
J 2
(-750 1175);
DISPLAY 0.553191 (-750 1175);
DISPLAY INVISIBLE (-750 1175);
FORCEPROP 2 LAST TOLERANCE 20%
J 2
(-650 1175);
DISPLAY 0.553191 (-650 1175);
DISPLAY INVISIBLE (-650 1175);
FORCEPROP 1 LAST PART_NUMBER SP_CH4221MEE01
J 2
(-691 1213);
DISPLAY 0.574468 (-691 1213);
PAINT GREEN (-691 1213);
DISPLAY INVISIBLE (-691 1213);
FORCEPROP 1 LAST LOCATION C925
J 0
(-325 1200);
DISPLAY 1.021277 (-325 1200);
DISPLAY INVISIBLE (-325 1200);
FORCEPROP 1 LAST PATH I29
J 2
(-575 1125);
DISPLAY 0.723404 (-575 1125);
DISPLAY INVISIBLE (-575 1125);
FORCEADD OFFPAGE..1
(-2500 3725);
FORCEPROP 2 LAST $XR0 24 
J 0
(-2751 3725);
DISPLAY 0.638298 (-2751 3725);
PAINT MONO (-2751 3725);
FORCEPROP 2 LAST CDS_LIB standard
J 0
(-2500 3725);
DISPLAY INVISIBLE (-2500 3725);
FORCEPROP 1 LAST OFFPAGE TRUE
J 0
(-2175 3600);
DISPLAY 0.872340 (-2175 3600);
DISPLAY INVISIBLE (-2175 3600);
FORCEPROP 1 LAST COMMENT_BODY TRUE
J 0
(-2375 3625);
DISPLAY 0.872340 (-2375 3625);
PAINT GREEN (-2375 3625);
DISPLAY INVISIBLE (-2375 3625);
FORCEPROP 2 LAST PATH I3
J 0
(-2775 3775);
DISPLAY 1.021277 (-2775 3775);
DISPLAY INVISIBLE (-2775 3775);
FORCEADD Q_CAP_DIFFBUS..2
R 2
(-575 1175);
FORCEPROP 1 LAST LOCATION C924
J 2
(-341 1192);
DISPLAY 0.723404 (-341 1192);
PAINT GREEN (-341 1192);
FORCEPROP 2 LAST $SEC 1
J 2
(-400 1250);
DISPLAY 0.680851 (-400 1250);
PAINT MONO (-400 1250);
DISPLAY INVISIBLE (-400 1250);
FORCEPROP 2 LAST CDS_SEC 1
J 2
(-400 1250);
DISPLAY 0.680851 (-400 1250);
DISPLAY INVISIBLE (-400 1250);
FORCEPROP 2 LASTPIN (-500 1175) $PN 1
J 0
(-490 1185);
DISPLAY 0.808511 (-490 1185);
FORCEPROP 2 LASTPIN (-650 1175) $PN 2
J 2
(-660 1185);
DISPLAY 0.808511 (-660 1185);
FORCEPROP 2 LAST VALUE DIFF BUS_0.22UF
J 2
(-725 1175);
DISPLAY 0.553191 (-725 1175);
FORCEPROP 1 LAST PIN_NAMES_ROTATE TRUE
J 2
(-575 1175);
DISPLAY 0.489362 (-575 1175);
PAINT GREEN (-575 1175);
DISPLAY INVISIBLE (-575 1175);
FORCEPROP 2 LAST CDS_LIB pure_quanta
J 2
(-575 1175);
DISPLAY INVISIBLE (-575 1175);
FORCEPROP 1 LAST CDS_LMAN_SYM_OUTLINE -25,50,25,-50
J 2
(-575 1175);
DISPLAY 0.468085 (-575 1175);
PAINT GREEN (-575 1175);
DISPLAY INVISIBLE (-575 1175);
FORCEPROP 2 LAST VOLTAGE 6.3V
J 2
(-925 1225);
DISPLAY 0.553191 (-925 1225);
DISPLAY INVISIBLE (-925 1225);
FORCEPROP 1 LAST MATERIAL X6S
J 2
(-566 1254);
DISPLAY 0.574468 (-566 1254);
PAINT GREEN (-566 1254);
DISPLAY INVISIBLE (-566 1254);
FORCEPROP 2 LAST PACK_TYPE C0201
J 2
(-750 1225);
DISPLAY 0.553191 (-750 1225);
DISPLAY INVISIBLE (-750 1225);
FORCEPROP 2 LAST TOLERANCE 20%
J 2
(-650 1225);
DISPLAY 0.553191 (-650 1225);
DISPLAY INVISIBLE (-650 1225);
FORCEPROP 1 LAST PART_NUMBER SP_CH4221MEE01
J 2
(-691 1263);
DISPLAY 0.574468 (-691 1263);
PAINT GREEN (-691 1263);
DISPLAY INVISIBLE (-691 1263);
FORCEPROP 1 LAST LOCATION C924
J 0
(-325 1250);
DISPLAY 1.021277 (-325 1250);
DISPLAY INVISIBLE (-325 1250);
FORCEPROP 1 LAST PATH I30
J 2
(-575 1175);
DISPLAY 0.723404 (-575 1175);
DISPLAY INVISIBLE (-575 1175);
FORCEADD Q_CAP_DIFFBUS..2
R 2
(-575 1325);
FORCEPROP 1 LAST LOCATION C923
J 2
(-341 1342);
DISPLAY 0.723404 (-341 1342);
PAINT GREEN (-341 1342);
FORCEPROP 2 LAST $SEC 1
J 2
(-400 1400);
DISPLAY 0.680851 (-400 1400);
PAINT MONO (-400 1400);
DISPLAY INVISIBLE (-400 1400);
FORCEPROP 2 LAST CDS_SEC 1
J 2
(-400 1400);
DISPLAY 0.680851 (-400 1400);
DISPLAY INVISIBLE (-400 1400);
FORCEPROP 2 LASTPIN (-500 1325) $PN 1
J 0
(-490 1335);
DISPLAY 0.808511 (-490 1335);
FORCEPROP 2 LASTPIN (-650 1325) $PN 2
J 2
(-660 1335);
DISPLAY 0.808511 (-660 1335);
FORCEPROP 2 LAST VALUE DIFF BUS_0.22UF
J 2
(-725 1325);
DISPLAY 0.553191 (-725 1325);
FORCEPROP 1 LAST PIN_NAMES_ROTATE TRUE
J 2
(-575 1325);
DISPLAY 0.489362 (-575 1325);
PAINT GREEN (-575 1325);
DISPLAY INVISIBLE (-575 1325);
FORCEPROP 2 LAST CDS_LIB pure_quanta
J 2
(-575 1325);
DISPLAY INVISIBLE (-575 1325);
FORCEPROP 1 LAST CDS_LMAN_SYM_OUTLINE -25,50,25,-50
J 2
(-575 1325);
DISPLAY 0.468085 (-575 1325);
PAINT GREEN (-575 1325);
DISPLAY INVISIBLE (-575 1325);
FORCEPROP 2 LAST VOLTAGE 6.3V
J 2
(-925 1375);
DISPLAY 0.553191 (-925 1375);
DISPLAY INVISIBLE (-925 1375);
FORCEPROP 1 LAST MATERIAL X6S
J 2
(-566 1404);
DISPLAY 0.574468 (-566 1404);
PAINT GREEN (-566 1404);
DISPLAY INVISIBLE (-566 1404);
FORCEPROP 2 LAST PACK_TYPE C0201
J 2
(-750 1375);
DISPLAY 0.553191 (-750 1375);
DISPLAY INVISIBLE (-750 1375);
FORCEPROP 2 LAST TOLERANCE 20%
J 2
(-650 1375);
DISPLAY 0.553191 (-650 1375);
DISPLAY INVISIBLE (-650 1375);
FORCEPROP 1 LAST PART_NUMBER SP_CH4221MEE01
J 2
(-691 1413);
DISPLAY 0.574468 (-691 1413);
PAINT GREEN (-691 1413);
DISPLAY INVISIBLE (-691 1413);
FORCEPROP 1 LAST LOCATION C923
J 0
(-325 1400);
DISPLAY 1.021277 (-325 1400);
DISPLAY INVISIBLE (-325 1400);
FORCEPROP 1 LAST PATH I31
J 2
(-575 1325);
DISPLAY 0.723404 (-575 1325);
DISPLAY INVISIBLE (-575 1325);
FORCEADD Q_CAP_DIFFBUS..2
R 2
(-575 1375);
FORCEPROP 1 LAST LOCATION C922
J 2
(-341 1392);
DISPLAY 0.723404 (-341 1392);
PAINT GREEN (-341 1392);
FORCEPROP 2 LAST $SEC 1
J 2
(-400 1450);
DISPLAY 0.680851 (-400 1450);
PAINT MONO (-400 1450);
DISPLAY INVISIBLE (-400 1450);
FORCEPROP 2 LAST CDS_SEC 1
J 2
(-400 1450);
DISPLAY 0.680851 (-400 1450);
DISPLAY INVISIBLE (-400 1450);
FORCEPROP 2 LASTPIN (-500 1375) $PN 1
J 0
(-490 1385);
DISPLAY 0.808511 (-490 1385);
FORCEPROP 2 LASTPIN (-650 1375) $PN 2
J 2
(-660 1385);
DISPLAY 0.808511 (-660 1385);
FORCEPROP 2 LAST VALUE DIFF BUS_0.22UF
J 2
(-725 1375);
DISPLAY 0.553191 (-725 1375);
FORCEPROP 1 LAST PIN_NAMES_ROTATE TRUE
J 2
(-575 1375);
DISPLAY 0.489362 (-575 1375);
PAINT GREEN (-575 1375);
DISPLAY INVISIBLE (-575 1375);
FORCEPROP 2 LAST CDS_LIB pure_quanta
J 2
(-575 1375);
DISPLAY INVISIBLE (-575 1375);
FORCEPROP 1 LAST CDS_LMAN_SYM_OUTLINE -25,50,25,-50
J 2
(-575 1375);
DISPLAY 0.468085 (-575 1375);
PAINT GREEN (-575 1375);
DISPLAY INVISIBLE (-575 1375);
FORCEPROP 2 LAST VOLTAGE 6.3V
J 2
(-925 1425);
DISPLAY 0.553191 (-925 1425);
DISPLAY INVISIBLE (-925 1425);
FORCEPROP 1 LAST MATERIAL X6S
J 2
(-566 1454);
DISPLAY 0.574468 (-566 1454);
PAINT GREEN (-566 1454);
DISPLAY INVISIBLE (-566 1454);
FORCEPROP 2 LAST PACK_TYPE C0201
J 2
(-750 1425);
DISPLAY 0.553191 (-750 1425);
DISPLAY INVISIBLE (-750 1425);
FORCEPROP 2 LAST TOLERANCE 20%
J 2
(-650 1425);
DISPLAY 0.553191 (-650 1425);
DISPLAY INVISIBLE (-650 1425);
FORCEPROP 1 LAST PART_NUMBER SP_CH4221MEE01
J 2
(-691 1463);
DISPLAY 0.574468 (-691 1463);
PAINT GREEN (-691 1463);
DISPLAY INVISIBLE (-691 1463);
FORCEPROP 1 LAST LOCATION C922
J 0
(-325 1450);
DISPLAY 1.021277 (-325 1450);
DISPLAY INVISIBLE (-325 1450);
FORCEPROP 1 LAST PATH I32
J 2
(-575 1375);
DISPLAY 0.723404 (-575 1375);
DISPLAY INVISIBLE (-575 1375);
FORCEADD Q_CAP_DIFFBUS..2
R 2
(-575 1525);
FORCEPROP 1 LAST LOCATION C921
J 2
(-341 1542);
DISPLAY 0.723404 (-341 1542);
PAINT GREEN (-341 1542);
FORCEPROP 2 LAST $SEC 1
J 2
(-400 1600);
DISPLAY 0.680851 (-400 1600);
PAINT MONO (-400 1600);
DISPLAY INVISIBLE (-400 1600);
FORCEPROP 2 LAST CDS_SEC 1
J 2
(-400 1600);
DISPLAY 0.680851 (-400 1600);
DISPLAY INVISIBLE (-400 1600);
FORCEPROP 2 LASTPIN (-500 1525) $PN 1
J 0
(-490 1535);
DISPLAY 0.808511 (-490 1535);
FORCEPROP 2 LASTPIN (-650 1525) $PN 2
J 2
(-660 1535);
DISPLAY 0.808511 (-660 1535);
FORCEPROP 2 LAST VALUE DIFF BUS_0.22UF
J 2
(-725 1525);
DISPLAY 0.553191 (-725 1525);
FORCEPROP 1 LAST PIN_NAMES_ROTATE TRUE
J 2
(-575 1525);
DISPLAY 0.489362 (-575 1525);
PAINT GREEN (-575 1525);
DISPLAY INVISIBLE (-575 1525);
FORCEPROP 2 LAST CDS_LIB pure_quanta
J 2
(-575 1525);
DISPLAY INVISIBLE (-575 1525);
FORCEPROP 1 LAST CDS_LMAN_SYM_OUTLINE -25,50,25,-50
J 2
(-575 1525);
DISPLAY 0.468085 (-575 1525);
PAINT GREEN (-575 1525);
DISPLAY INVISIBLE (-575 1525);
FORCEPROP 2 LAST VOLTAGE 6.3V
J 2
(-925 1575);
DISPLAY 0.553191 (-925 1575);
DISPLAY INVISIBLE (-925 1575);
FORCEPROP 1 LAST MATERIAL X6S
J 2
(-566 1604);
DISPLAY 0.574468 (-566 1604);
PAINT GREEN (-566 1604);
DISPLAY INVISIBLE (-566 1604);
FORCEPROP 2 LAST PACK_TYPE C0201
J 2
(-750 1575);
DISPLAY 0.553191 (-750 1575);
DISPLAY INVISIBLE (-750 1575);
FORCEPROP 2 LAST TOLERANCE 20%
J 2
(-650 1575);
DISPLAY 0.553191 (-650 1575);
DISPLAY INVISIBLE (-650 1575);
FORCEPROP 1 LAST PART_NUMBER SP_CH4221MEE01
J 2
(-691 1613);
DISPLAY 0.574468 (-691 1613);
PAINT GREEN (-691 1613);
DISPLAY INVISIBLE (-691 1613);
FORCEPROP 1 LAST LOCATION C921
J 0
(-325 1600);
DISPLAY 1.021277 (-325 1600);
DISPLAY INVISIBLE (-325 1600);
FORCEPROP 1 LAST PATH I33
J 2
(-575 1525);
DISPLAY 0.723404 (-575 1525);
DISPLAY INVISIBLE (-575 1525);
FORCEADD Q_CAP_DIFFBUS..2
R 2
(-575 1575);
FORCEPROP 1 LAST LOCATION C920
J 2
(-341 1592);
DISPLAY 0.723404 (-341 1592);
PAINT GREEN (-341 1592);
FORCEPROP 2 LAST $SEC 1
J 2
(-400 1650);
DISPLAY 0.680851 (-400 1650);
PAINT MONO (-400 1650);
DISPLAY INVISIBLE (-400 1650);
FORCEPROP 2 LAST CDS_SEC 1
J 2
(-400 1650);
DISPLAY 0.680851 (-400 1650);
DISPLAY INVISIBLE (-400 1650);
FORCEPROP 2 LASTPIN (-500 1575) $PN 1
J 0
(-490 1585);
DISPLAY 0.808511 (-490 1585);
FORCEPROP 2 LASTPIN (-650 1575) $PN 2
J 2
(-660 1585);
DISPLAY 0.808511 (-660 1585);
FORCEPROP 2 LAST VALUE DIFF BUS_0.22UF
J 2
(-725 1575);
DISPLAY 0.553191 (-725 1575);
FORCEPROP 1 LAST PIN_NAMES_ROTATE TRUE
J 2
(-575 1575);
DISPLAY 0.489362 (-575 1575);
PAINT GREEN (-575 1575);
DISPLAY INVISIBLE (-575 1575);
FORCEPROP 2 LAST CDS_LIB pure_quanta
J 2
(-575 1575);
DISPLAY INVISIBLE (-575 1575);
FORCEPROP 1 LAST CDS_LMAN_SYM_OUTLINE -25,50,25,-50
J 2
(-575 1575);
DISPLAY 0.468085 (-575 1575);
PAINT GREEN (-575 1575);
DISPLAY INVISIBLE (-575 1575);
FORCEPROP 2 LAST VOLTAGE 6.3V
J 2
(-925 1625);
DISPLAY 0.553191 (-925 1625);
DISPLAY INVISIBLE (-925 1625);
FORCEPROP 1 LAST MATERIAL X6S
J 2
(-566 1654);
DISPLAY 0.574468 (-566 1654);
PAINT GREEN (-566 1654);
DISPLAY INVISIBLE (-566 1654);
FORCEPROP 2 LAST PACK_TYPE C0201
J 2
(-750 1625);
DISPLAY 0.553191 (-750 1625);
DISPLAY INVISIBLE (-750 1625);
FORCEPROP 2 LAST TOLERANCE 20%
J 2
(-650 1625);
DISPLAY 0.553191 (-650 1625);
DISPLAY INVISIBLE (-650 1625);
FORCEPROP 1 LAST PART_NUMBER SP_CH4221MEE01
J 2
(-691 1663);
DISPLAY 0.574468 (-691 1663);
PAINT GREEN (-691 1663);
DISPLAY INVISIBLE (-691 1663);
FORCEPROP 1 LAST LOCATION C920
J 0
(-325 1650);
DISPLAY 1.021277 (-325 1650);
DISPLAY INVISIBLE (-325 1650);
FORCEPROP 1 LAST PATH I34
J 2
(-575 1575);
DISPLAY 0.723404 (-575 1575);
DISPLAY INVISIBLE (-575 1575);
FORCEADD Q_CAP_DIFFBUS..2
R 2
(-575 1775);
FORCEPROP 1 LAST LOCATION C918
J 2
(-341 1792);
DISPLAY 0.723404 (-341 1792);
PAINT GREEN (-341 1792);
FORCEPROP 2 LAST $SEC 1
J 2
(-400 1850);
DISPLAY 0.680851 (-400 1850);
PAINT MONO (-400 1850);
DISPLAY INVISIBLE (-400 1850);
FORCEPROP 2 LAST CDS_SEC 1
J 2
(-400 1850);
DISPLAY 0.680851 (-400 1850);
DISPLAY INVISIBLE (-400 1850);
FORCEPROP 2 LASTPIN (-500 1775) $PN 1
J 0
(-490 1785);
DISPLAY 0.808511 (-490 1785);
FORCEPROP 2 LASTPIN (-650 1775) $PN 2
J 2
(-660 1785);
DISPLAY 0.808511 (-660 1785);
FORCEPROP 2 LAST VALUE DIFF BUS_0.22UF
J 2
(-725 1775);
DISPLAY 0.553191 (-725 1775);
FORCEPROP 1 LAST PIN_NAMES_ROTATE TRUE
J 2
(-575 1775);
DISPLAY 0.489362 (-575 1775);
PAINT GREEN (-575 1775);
DISPLAY INVISIBLE (-575 1775);
FORCEPROP 1 LAST CDS_LMAN_SYM_OUTLINE -25,50,25,-50
J 2
(-575 1775);
DISPLAY 0.468085 (-575 1775);
PAINT GREEN (-575 1775);
DISPLAY INVISIBLE (-575 1775);
FORCEPROP 2 LAST CDS_LIB pure_quanta
J 2
(-575 1775);
DISPLAY INVISIBLE (-575 1775);
FORCEPROP 2 LAST VOLTAGE 6.3V
J 2
(-925 1825);
DISPLAY 0.553191 (-925 1825);
DISPLAY INVISIBLE (-925 1825);
FORCEPROP 1 LAST MATERIAL X6S
J 2
(-566 1854);
DISPLAY 0.574468 (-566 1854);
PAINT GREEN (-566 1854);
DISPLAY INVISIBLE (-566 1854);
FORCEPROP 2 LAST PACK_TYPE C0201
J 2
(-750 1825);
DISPLAY 0.553191 (-750 1825);
DISPLAY INVISIBLE (-750 1825);
FORCEPROP 2 LAST TOLERANCE 20%
J 2
(-650 1825);
DISPLAY 0.553191 (-650 1825);
DISPLAY INVISIBLE (-650 1825);
FORCEPROP 1 LAST PART_NUMBER SP_CH4221MEE01
J 2
(-691 1863);
DISPLAY 0.574468 (-691 1863);
PAINT GREEN (-691 1863);
DISPLAY INVISIBLE (-691 1863);
FORCEPROP 1 LAST LOCATION C918
J 0
(-325 1850);
DISPLAY 1.021277 (-325 1850);
DISPLAY INVISIBLE (-325 1850);
FORCEPROP 1 LAST PATH I35
J 2
(-575 1775);
DISPLAY 0.723404 (-575 1775);
DISPLAY INVISIBLE (-575 1775);
FORCEADD Q_CAP_DIFFBUS..2
R 2
(-575 1725);
FORCEPROP 1 LAST LOCATION C919
J 2
(-341 1742);
DISPLAY 0.723404 (-341 1742);
PAINT GREEN (-341 1742);
FORCEPROP 2 LAST $SEC 1
J 2
(-400 1800);
DISPLAY 0.680851 (-400 1800);
PAINT MONO (-400 1800);
DISPLAY INVISIBLE (-400 1800);
FORCEPROP 2 LAST CDS_SEC 1
J 2
(-400 1800);
DISPLAY 0.680851 (-400 1800);
DISPLAY INVISIBLE (-400 1800);
FORCEPROP 2 LASTPIN (-500 1725) $PN 1
J 0
(-490 1735);
DISPLAY 0.808511 (-490 1735);
FORCEPROP 2 LASTPIN (-650 1725) $PN 2
J 2
(-660 1735);
DISPLAY 0.808511 (-660 1735);
FORCEPROP 2 LAST VALUE DIFF BUS_0.22UF
J 2
(-725 1725);
DISPLAY 0.553191 (-725 1725);
FORCEPROP 1 LAST PIN_NAMES_ROTATE TRUE
J 2
(-575 1725);
DISPLAY 0.489362 (-575 1725);
PAINT GREEN (-575 1725);
DISPLAY INVISIBLE (-575 1725);
FORCEPROP 2 LAST CDS_LIB pure_quanta
J 2
(-575 1725);
DISPLAY INVISIBLE (-575 1725);
FORCEPROP 1 LAST CDS_LMAN_SYM_OUTLINE -25,50,25,-50
J 2
(-575 1725);
DISPLAY 0.468085 (-575 1725);
PAINT GREEN (-575 1725);
DISPLAY INVISIBLE (-575 1725);
FORCEPROP 2 LAST VOLTAGE 6.3V
J 2
(-925 1775);
DISPLAY 0.553191 (-925 1775);
DISPLAY INVISIBLE (-925 1775);
FORCEPROP 1 LAST MATERIAL X6S
J 2
(-566 1804);
DISPLAY 0.574468 (-566 1804);
PAINT GREEN (-566 1804);
DISPLAY INVISIBLE (-566 1804);
FORCEPROP 2 LAST PACK_TYPE C0201
J 2
(-750 1775);
DISPLAY 0.553191 (-750 1775);
DISPLAY INVISIBLE (-750 1775);
FORCEPROP 2 LAST TOLERANCE 20%
J 2
(-650 1775);
DISPLAY 0.553191 (-650 1775);
DISPLAY INVISIBLE (-650 1775);
FORCEPROP 1 LAST PART_NUMBER SP_CH4221MEE01
J 2
(-691 1813);
DISPLAY 0.574468 (-691 1813);
PAINT GREEN (-691 1813);
DISPLAY INVISIBLE (-691 1813);
FORCEPROP 1 LAST LOCATION C919
J 0
(-325 1800);
DISPLAY 1.021277 (-325 1800);
DISPLAY INVISIBLE (-325 1800);
FORCEPROP 1 LAST PATH I36
J 2
(-575 1725);
DISPLAY 0.723404 (-575 1725);
DISPLAY INVISIBLE (-575 1725);
FORCEADD TAP..1
R 2
(-1550 2300);
FORCEPROP 3 LASTPIN (-1500 2300) SIG_NAME P5E_CPU0_P0_TX_DP<8>
J 0
(-1490 2310);
DISPLAY 0.659574 (-1490 2310);
PAINT MONO (-1490 2310);
DISPLAY INVISIBLE (-1490 2310);
FORCEPROP 1 LASTPIN (-1500 2300) BN 8
J 2
(-1488 2308);
DISPLAY 0.680851 (-1488 2308);
PAINT GREEN (-1488 2308);
FORCEPROP 2 LAST CDS_LIB standard
J 0
(-1550 2300);
DISPLAY INVISIBLE (-1550 2300);
FORCEPROP 1 LAST BODY_TYPE PLUMBING
J 2
(-1550 2350);
DISPLAY 0.872340 (-1550 2350);
PAINT GREEN (-1550 2350);
DISPLAY INVISIBLE (-1550 2350);
FORCEPROP 1 LAST HDL_TAP TRUE
J 2
(-1875 2175);
DISPLAY 0.872340 (-1875 2175);
DISPLAY INVISIBLE (-1875 2175);
FORCEPROP 1 LAST PATH I37
J 2
(-1548 2300);
DISPLAY 0.872340 (-1548 2300);
PAINT GREEN (-1548 2300);
DISPLAY INVISIBLE (-1548 2300);
FORCEADD TAP..1
R 2
(-1550 2500);
FORCEPROP 3 LASTPIN (-1500 2500) SIG_NAME P5E_CPU0_P0_TX_DP<9>
J 0
(-1490 2510);
DISPLAY 0.659574 (-1490 2510);
PAINT MONO (-1490 2510);
DISPLAY INVISIBLE (-1490 2510);
FORCEPROP 1 LASTPIN (-1500 2500) BN 9
J 2
(-1488 2508);
DISPLAY 0.680851 (-1488 2508);
PAINT GREEN (-1488 2508);
FORCEPROP 2 LAST CDS_LIB standard
J 0
(-1550 2500);
DISPLAY INVISIBLE (-1550 2500);
FORCEPROP 1 LAST BODY_TYPE PLUMBING
J 2
(-1550 2550);
DISPLAY 0.872340 (-1550 2550);
PAINT GREEN (-1550 2550);
DISPLAY INVISIBLE (-1550 2550);
FORCEPROP 1 LAST HDL_TAP TRUE
J 2
(-1875 2375);
DISPLAY 0.872340 (-1875 2375);
DISPLAY INVISIBLE (-1875 2375);
FORCEPROP 1 LAST PATH I38
J 2
(-1548 2500);
DISPLAY 0.872340 (-1548 2500);
PAINT GREEN (-1548 2500);
DISPLAY INVISIBLE (-1548 2500);
FORCEADD TAP..1
R 2
(-1300 2350);
FORCEPROP 3 LASTPIN (-1250 2350) SIG_NAME P5E_CPU0_P0_TX_DN<8>
J 0
(-1240 2360);
DISPLAY 0.659574 (-1240 2360);
PAINT MONO (-1240 2360);
DISPLAY INVISIBLE (-1240 2360);
FORCEPROP 1 LASTPIN (-1250 2350) BN 8
J 2
(-1238 2358);
DISPLAY 0.680851 (-1238 2358);
PAINT GREEN (-1238 2358);
FORCEPROP 2 LAST CDS_LIB standard
J 0
(-1300 2350);
DISPLAY INVISIBLE (-1300 2350);
FORCEPROP 1 LAST BODY_TYPE PLUMBING
J 2
(-1300 2400);
DISPLAY 0.872340 (-1300 2400);
PAINT GREEN (-1300 2400);
DISPLAY INVISIBLE (-1300 2400);
FORCEPROP 1 LAST HDL_TAP TRUE
J 2
(-1625 2225);
DISPLAY 0.872340 (-1625 2225);
DISPLAY INVISIBLE (-1625 2225);
FORCEPROP 1 LAST PATH I39
J 2
(-1298 2350);
DISPLAY 0.872340 (-1298 2350);
PAINT GREEN (-1298 2350);
DISPLAY INVISIBLE (-1298 2350);
FORCEADD OFFPAGE..1
(-2500 3775);
FORCEPROP 2 LAST $XR0 24 
J 0
(-2751 3775);
DISPLAY 0.638298 (-2751 3775);
PAINT MONO (-2751 3775);
FORCEPROP 2 LAST CDS_LIB standard
J 0
(-2500 3775);
DISPLAY INVISIBLE (-2500 3775);
FORCEPROP 1 LAST OFFPAGE TRUE
J 0
(-2175 3650);
DISPLAY 0.872340 (-2175 3650);
DISPLAY INVISIBLE (-2175 3650);
FORCEPROP 1 LAST COMMENT_BODY TRUE
J 0
(-2375 3675);
DISPLAY 0.872340 (-2375 3675);
PAINT GREEN (-2375 3675);
DISPLAY INVISIBLE (-2375 3675);
FORCEPROP 2 LAST PATH I4
J 0
(-2775 3825);
DISPLAY 1.021277 (-2775 3825);
DISPLAY INVISIBLE (-2775 3825);
FORCEADD TAP..1
R 2
(-1300 2550);
FORCEPROP 3 LASTPIN (-1250 2550) SIG_NAME P5E_CPU0_P0_TX_DN<9>
J 0
(-1240 2560);
DISPLAY 0.659574 (-1240 2560);
PAINT MONO (-1240 2560);
DISPLAY INVISIBLE (-1240 2560);
FORCEPROP 1 LASTPIN (-1250 2550) BN 9
J 2
(-1238 2558);
DISPLAY 0.680851 (-1238 2558);
PAINT GREEN (-1238 2558);
FORCEPROP 2 LAST CDS_LIB standard
J 0
(-1300 2550);
DISPLAY INVISIBLE (-1300 2550);
FORCEPROP 1 LAST BODY_TYPE PLUMBING
J 2
(-1300 2600);
DISPLAY 0.872340 (-1300 2600);
PAINT GREEN (-1300 2600);
DISPLAY INVISIBLE (-1300 2600);
FORCEPROP 1 LAST HDL_TAP TRUE
J 2
(-1625 2425);
DISPLAY 0.872340 (-1625 2425);
DISPLAY INVISIBLE (-1625 2425);
FORCEPROP 1 LAST PATH I40
J 2
(-1298 2550);
DISPLAY 0.872340 (-1298 2550);
PAINT GREEN (-1298 2550);
DISPLAY INVISIBLE (-1298 2550);
FORCEADD TAP..1
R 2
(-1550 2700);
FORCEPROP 3 LASTPIN (-1500 2700) SIG_NAME P5E_CPU0_P0_TX_DP<10>
J 0
(-1490 2710);
DISPLAY 0.659574 (-1490 2710);
PAINT MONO (-1490 2710);
DISPLAY INVISIBLE (-1490 2710);
FORCEPROP 1 LASTPIN (-1500 2700) BN 10
J 2
(-1488 2708);
DISPLAY 0.680851 (-1488 2708);
PAINT GREEN (-1488 2708);
FORCEPROP 2 LAST CDS_LIB standard
J 0
(-1550 2700);
DISPLAY INVISIBLE (-1550 2700);
FORCEPROP 1 LAST BODY_TYPE PLUMBING
J 2
(-1550 2750);
DISPLAY 0.872340 (-1550 2750);
PAINT GREEN (-1550 2750);
DISPLAY INVISIBLE (-1550 2750);
FORCEPROP 1 LAST HDL_TAP TRUE
J 2
(-1875 2575);
DISPLAY 0.872340 (-1875 2575);
DISPLAY INVISIBLE (-1875 2575);
FORCEPROP 1 LAST PATH I41
J 2
(-1548 2700);
DISPLAY 0.872340 (-1548 2700);
PAINT GREEN (-1548 2700);
DISPLAY INVISIBLE (-1548 2700);
FORCEADD TAP..1
R 2
(-1550 2900);
FORCEPROP 3 LASTPIN (-1500 2900) SIG_NAME P5E_CPU0_P0_TX_DP<11>
J 0
(-1490 2910);
DISPLAY 0.659574 (-1490 2910);
PAINT MONO (-1490 2910);
DISPLAY INVISIBLE (-1490 2910);
FORCEPROP 1 LASTPIN (-1500 2900) BN 11
J 2
(-1488 2908);
DISPLAY 0.680851 (-1488 2908);
PAINT GREEN (-1488 2908);
FORCEPROP 2 LAST CDS_LIB standard
J 0
(-1550 2900);
DISPLAY INVISIBLE (-1550 2900);
FORCEPROP 1 LAST BODY_TYPE PLUMBING
J 2
(-1550 2950);
DISPLAY 0.872340 (-1550 2950);
PAINT GREEN (-1550 2950);
DISPLAY INVISIBLE (-1550 2950);
FORCEPROP 1 LAST HDL_TAP TRUE
J 2
(-1875 2775);
DISPLAY 0.872340 (-1875 2775);
DISPLAY INVISIBLE (-1875 2775);
FORCEPROP 1 LAST PATH I42
J 2
(-1548 2900);
DISPLAY 0.872340 (-1548 2900);
PAINT GREEN (-1548 2900);
DISPLAY INVISIBLE (-1548 2900);
FORCEADD TAP..1
R 2
(-1550 3100);
FORCEPROP 3 LASTPIN (-1500 3100) SIG_NAME P5E_CPU0_P0_TX_DP<12>
J 0
(-1490 3110);
DISPLAY 0.659574 (-1490 3110);
PAINT MONO (-1490 3110);
DISPLAY INVISIBLE (-1490 3110);
FORCEPROP 1 LASTPIN (-1500 3100) BN 12
J 2
(-1488 3108);
DISPLAY 0.680851 (-1488 3108);
PAINT GREEN (-1488 3108);
FORCEPROP 2 LAST CDS_LIB standard
J 0
(-1550 3100);
DISPLAY INVISIBLE (-1550 3100);
FORCEPROP 1 LAST BODY_TYPE PLUMBING
J 2
(-1550 3150);
DISPLAY 0.872340 (-1550 3150);
PAINT GREEN (-1550 3150);
DISPLAY INVISIBLE (-1550 3150);
FORCEPROP 1 LAST HDL_TAP TRUE
J 2
(-1875 2975);
DISPLAY 0.872340 (-1875 2975);
DISPLAY INVISIBLE (-1875 2975);
FORCEPROP 1 LAST PATH I43
J 2
(-1548 3100);
DISPLAY 0.872340 (-1548 3100);
PAINT GREEN (-1548 3100);
DISPLAY INVISIBLE (-1548 3100);
FORCEADD TAP..1
R 2
(-1300 2750);
FORCEPROP 3 LASTPIN (-1250 2750) SIG_NAME P5E_CPU0_P0_TX_DN<10>
J 0
(-1240 2760);
DISPLAY 0.659574 (-1240 2760);
PAINT MONO (-1240 2760);
DISPLAY INVISIBLE (-1240 2760);
FORCEPROP 1 LASTPIN (-1250 2750) BN 10
J 2
(-1238 2758);
DISPLAY 0.680851 (-1238 2758);
PAINT GREEN (-1238 2758);
FORCEPROP 2 LAST CDS_LIB standard
J 0
(-1300 2750);
DISPLAY INVISIBLE (-1300 2750);
FORCEPROP 1 LAST BODY_TYPE PLUMBING
J 2
(-1300 2800);
DISPLAY 0.872340 (-1300 2800);
PAINT GREEN (-1300 2800);
DISPLAY INVISIBLE (-1300 2800);
FORCEPROP 1 LAST HDL_TAP TRUE
J 2
(-1625 2625);
DISPLAY 0.872340 (-1625 2625);
DISPLAY INVISIBLE (-1625 2625);
FORCEPROP 1 LAST PATH I44
J 2
(-1298 2750);
DISPLAY 0.872340 (-1298 2750);
PAINT GREEN (-1298 2750);
DISPLAY INVISIBLE (-1298 2750);
FORCEADD TAP..1
R 2
(-1300 2950);
FORCEPROP 3 LASTPIN (-1250 2950) SIG_NAME P5E_CPU0_P0_TX_DN<11>
J 0
(-1240 2960);
DISPLAY 0.659574 (-1240 2960);
PAINT MONO (-1240 2960);
DISPLAY INVISIBLE (-1240 2960);
FORCEPROP 1 LASTPIN (-1250 2950) BN 11
J 2
(-1238 2958);
DISPLAY 0.680851 (-1238 2958);
PAINT GREEN (-1238 2958);
FORCEPROP 2 LAST CDS_LIB standard
J 0
(-1300 2950);
DISPLAY INVISIBLE (-1300 2950);
FORCEPROP 1 LAST BODY_TYPE PLUMBING
J 2
(-1300 3000);
DISPLAY 0.872340 (-1300 3000);
PAINT GREEN (-1300 3000);
DISPLAY INVISIBLE (-1300 3000);
FORCEPROP 1 LAST HDL_TAP TRUE
J 2
(-1625 2825);
DISPLAY 0.872340 (-1625 2825);
DISPLAY INVISIBLE (-1625 2825);
FORCEPROP 1 LAST PATH I45
J 2
(-1298 2950);
DISPLAY 0.872340 (-1298 2950);
PAINT GREEN (-1298 2950);
DISPLAY INVISIBLE (-1298 2950);
FORCEADD TAP..1
R 2
(-1300 3150);
FORCEPROP 3 LASTPIN (-1250 3150) SIG_NAME P5E_CPU0_P0_TX_DN<12>
J 0
(-1240 3160);
DISPLAY 0.659574 (-1240 3160);
PAINT MONO (-1240 3160);
DISPLAY INVISIBLE (-1240 3160);
FORCEPROP 1 LASTPIN (-1250 3150) BN 12
J 2
(-1238 3158);
DISPLAY 0.680851 (-1238 3158);
PAINT GREEN (-1238 3158);
FORCEPROP 2 LAST CDS_LIB standard
J 0
(-1300 3150);
DISPLAY INVISIBLE (-1300 3150);
FORCEPROP 1 LAST BODY_TYPE PLUMBING
J 2
(-1300 3200);
DISPLAY 0.872340 (-1300 3200);
PAINT GREEN (-1300 3200);
DISPLAY INVISIBLE (-1300 3200);
FORCEPROP 1 LAST HDL_TAP TRUE
J 2
(-1625 3025);
DISPLAY 0.872340 (-1625 3025);
DISPLAY INVISIBLE (-1625 3025);
FORCEPROP 1 LAST PATH I46
J 2
(-1298 3150);
DISPLAY 0.872340 (-1298 3150);
PAINT GREEN (-1298 3150);
DISPLAY INVISIBLE (-1298 3150);
FORCEADD TAP..1
R 2
(-1550 3300);
FORCEPROP 3 LASTPIN (-1500 3300) SIG_NAME P5E_CPU0_P0_TX_DP<13>
J 0
(-1490 3310);
DISPLAY 0.659574 (-1490 3310);
PAINT MONO (-1490 3310);
DISPLAY INVISIBLE (-1490 3310);
FORCEPROP 1 LASTPIN (-1500 3300) BN 13
J 2
(-1488 3308);
DISPLAY 0.680851 (-1488 3308);
PAINT GREEN (-1488 3308);
FORCEPROP 2 LAST CDS_LIB standard
J 0
(-1550 3300);
DISPLAY INVISIBLE (-1550 3300);
FORCEPROP 1 LAST BODY_TYPE PLUMBING
J 2
(-1550 3350);
DISPLAY 0.872340 (-1550 3350);
PAINT GREEN (-1550 3350);
DISPLAY INVISIBLE (-1550 3350);
FORCEPROP 1 LAST HDL_TAP TRUE
J 2
(-1875 3175);
DISPLAY 0.872340 (-1875 3175);
DISPLAY INVISIBLE (-1875 3175);
FORCEPROP 1 LAST PATH I47
J 2
(-1548 3300);
DISPLAY 0.872340 (-1548 3300);
PAINT GREEN (-1548 3300);
DISPLAY INVISIBLE (-1548 3300);
FORCEADD TAP..1
R 2
(-1550 3500);
FORCEPROP 3 LASTPIN (-1500 3500) SIG_NAME P5E_CPU0_P0_TX_DP<14>
J 0
(-1490 3510);
DISPLAY 0.659574 (-1490 3510);
PAINT MONO (-1490 3510);
DISPLAY INVISIBLE (-1490 3510);
FORCEPROP 1 LASTPIN (-1500 3500) BN 14
J 2
(-1488 3508);
DISPLAY 0.680851 (-1488 3508);
PAINT GREEN (-1488 3508);
FORCEPROP 2 LAST CDS_LIB standard
J 0
(-1550 3500);
DISPLAY INVISIBLE (-1550 3500);
FORCEPROP 1 LAST BODY_TYPE PLUMBING
J 2
(-1550 3550);
DISPLAY 0.872340 (-1550 3550);
PAINT GREEN (-1550 3550);
DISPLAY INVISIBLE (-1550 3550);
FORCEPROP 1 LAST HDL_TAP TRUE
J 2
(-1875 3375);
DISPLAY 0.872340 (-1875 3375);
DISPLAY INVISIBLE (-1875 3375);
FORCEPROP 1 LAST PATH I48
J 2
(-1548 3500);
DISPLAY 0.872340 (-1548 3500);
PAINT GREEN (-1548 3500);
DISPLAY INVISIBLE (-1548 3500);
FORCEADD TAP..1
R 2
(-1550 3700);
FORCEPROP 3 LASTPIN (-1500 3700) SIG_NAME P5E_CPU0_P0_TX_DP<15>
J 0
(-1490 3710);
DISPLAY 0.659574 (-1490 3710);
PAINT MONO (-1490 3710);
DISPLAY INVISIBLE (-1490 3710);
FORCEPROP 1 LASTPIN (-1500 3700) BN 15
J 2
(-1488 3708);
DISPLAY 0.680851 (-1488 3708);
PAINT GREEN (-1488 3708);
FORCEPROP 2 LAST CDS_LIB standard
J 0
(-1550 3700);
DISPLAY INVISIBLE (-1550 3700);
FORCEPROP 1 LAST BODY_TYPE PLUMBING
J 2
(-1550 3750);
DISPLAY 0.872340 (-1550 3750);
PAINT GREEN (-1550 3750);
DISPLAY INVISIBLE (-1550 3750);
FORCEPROP 1 LAST HDL_TAP TRUE
J 2
(-1875 3575);
DISPLAY 0.872340 (-1875 3575);
DISPLAY INVISIBLE (-1875 3575);
FORCEPROP 1 LAST PATH I49
J 2
(-1548 3700);
DISPLAY 0.872340 (-1548 3700);
PAINT GREEN (-1548 3700);
DISPLAY INVISIBLE (-1548 3700);
FORCEADD TAP..1
R 2
(-1550 325);
FORCEPROP 3 LASTPIN (-1500 325) SIG_NAME P5E_CPU0_P0_TX_DP<0>
J 0
(-1490 335);
DISPLAY 0.659574 (-1490 335);
PAINT MONO (-1490 335);
DISPLAY INVISIBLE (-1490 335);
FORCEPROP 1 LASTPIN (-1500 325) BN 0
J 2
(-1488 333);
DISPLAY 0.680851 (-1488 333);
PAINT GREEN (-1488 333);
FORCEPROP 2 LAST CDS_LIB standard
J 0
(-1550 325);
DISPLAY INVISIBLE (-1550 325);
FORCEPROP 1 LAST BODY_TYPE PLUMBING
J 2
(-1550 375);
DISPLAY 0.872340 (-1550 375);
PAINT GREEN (-1550 375);
DISPLAY INVISIBLE (-1550 375);
FORCEPROP 1 LAST HDL_TAP TRUE
J 2
(-1875 200);
DISPLAY 0.872340 (-1875 200);
DISPLAY INVISIBLE (-1875 200);
FORCEPROP 1 LAST PATH I5
J 2
(-1548 325);
DISPLAY 0.872340 (-1548 325);
PAINT GREEN (-1548 325);
DISPLAY INVISIBLE (-1548 325);
FORCEADD TAP..1
R 2
(-1300 3350);
FORCEPROP 3 LASTPIN (-1250 3350) SIG_NAME P5E_CPU0_P0_TX_DN<13>
J 0
(-1240 3360);
DISPLAY 0.659574 (-1240 3360);
PAINT MONO (-1240 3360);
DISPLAY INVISIBLE (-1240 3360);
FORCEPROP 1 LASTPIN (-1250 3350) BN 13
J 2
(-1238 3358);
DISPLAY 0.680851 (-1238 3358);
PAINT GREEN (-1238 3358);
FORCEPROP 2 LAST CDS_LIB standard
J 0
(-1300 3350);
DISPLAY INVISIBLE (-1300 3350);
FORCEPROP 1 LAST BODY_TYPE PLUMBING
J 2
(-1300 3400);
DISPLAY 0.872340 (-1300 3400);
PAINT GREEN (-1300 3400);
DISPLAY INVISIBLE (-1300 3400);
FORCEPROP 1 LAST HDL_TAP TRUE
J 2
(-1625 3225);
DISPLAY 0.872340 (-1625 3225);
DISPLAY INVISIBLE (-1625 3225);
FORCEPROP 1 LAST PATH I50
J 2
(-1298 3350);
DISPLAY 0.872340 (-1298 3350);
PAINT GREEN (-1298 3350);
DISPLAY INVISIBLE (-1298 3350);
FORCEADD TAP..1
R 2
(-1300 3550);
FORCEPROP 3 LASTPIN (-1250 3550) SIG_NAME P5E_CPU0_P0_TX_DN<14>
J 0
(-1240 3560);
DISPLAY 0.659574 (-1240 3560);
PAINT MONO (-1240 3560);
DISPLAY INVISIBLE (-1240 3560);
FORCEPROP 1 LASTPIN (-1250 3550) BN 14
J 2
(-1238 3558);
DISPLAY 0.680851 (-1238 3558);
PAINT GREEN (-1238 3558);
FORCEPROP 2 LAST CDS_LIB standard
J 0
(-1300 3550);
DISPLAY INVISIBLE (-1300 3550);
FORCEPROP 1 LAST BODY_TYPE PLUMBING
J 2
(-1300 3600);
DISPLAY 0.872340 (-1300 3600);
PAINT GREEN (-1300 3600);
DISPLAY INVISIBLE (-1300 3600);
FORCEPROP 1 LAST HDL_TAP TRUE
J 2
(-1625 3425);
DISPLAY 0.872340 (-1625 3425);
DISPLAY INVISIBLE (-1625 3425);
FORCEPROP 1 LAST PATH I51
J 2
(-1298 3550);
DISPLAY 0.872340 (-1298 3550);
PAINT GREEN (-1298 3550);
DISPLAY INVISIBLE (-1298 3550);
FORCEADD TAP..1
R 2
(-1300 3750);
FORCEPROP 3 LASTPIN (-1250 3750) SIG_NAME P5E_CPU0_P0_TX_DN<15>
J 0
(-1240 3760);
DISPLAY 0.659574 (-1240 3760);
PAINT MONO (-1240 3760);
DISPLAY INVISIBLE (-1240 3760);
FORCEPROP 1 LASTPIN (-1250 3750) BN 15
J 2
(-1238 3758);
DISPLAY 0.680851 (-1238 3758);
PAINT GREEN (-1238 3758);
FORCEPROP 2 LAST CDS_LIB standard
J 0
(-1300 3750);
DISPLAY INVISIBLE (-1300 3750);
FORCEPROP 1 LAST BODY_TYPE PLUMBING
J 2
(-1300 3800);
DISPLAY 0.872340 (-1300 3800);
PAINT GREEN (-1300 3800);
DISPLAY INVISIBLE (-1300 3800);
FORCEPROP 1 LAST HDL_TAP TRUE
J 2
(-1625 3625);
DISPLAY 0.872340 (-1625 3625);
DISPLAY INVISIBLE (-1625 3625);
FORCEPROP 1 LAST PATH I52
J 2
(-1298 3750);
DISPLAY 0.872340 (-1298 3750);
PAINT GREEN (-1298 3750);
DISPLAY INVISIBLE (-1298 3750);
FORCEADD Q_CAP_DIFFBUS..2
R 2
(-575 2350);
FORCEPROP 1 LAST LOCATION C916
J 2
(-341 2367);
DISPLAY 0.723404 (-341 2367);
PAINT GREEN (-341 2367);
FORCEPROP 2 LAST $SEC 1
J 2
(-400 2425);
DISPLAY 0.680851 (-400 2425);
PAINT MONO (-400 2425);
DISPLAY INVISIBLE (-400 2425);
FORCEPROP 2 LAST CDS_SEC 1
J 2
(-400 2425);
DISPLAY 0.680851 (-400 2425);
DISPLAY INVISIBLE (-400 2425);
FORCEPROP 2 LASTPIN (-500 2350) $PN 1
J 0
(-490 2360);
DISPLAY 0.808511 (-490 2360);
FORCEPROP 2 LASTPIN (-650 2350) $PN 2
J 2
(-660 2360);
DISPLAY 0.808511 (-660 2360);
FORCEPROP 2 LAST VALUE DIFF BUS_0.22UF
J 2
(-725 2350);
DISPLAY 0.553191 (-725 2350);
FORCEPROP 1 LAST CDS_LMAN_SYM_OUTLINE -25,50,25,-50
J 2
(-575 2350);
DISPLAY 0.468085 (-575 2350);
PAINT GREEN (-575 2350);
DISPLAY INVISIBLE (-575 2350);
FORCEPROP 2 LAST CDS_LIB pure_quanta
J 2
(-575 2350);
DISPLAY INVISIBLE (-575 2350);
FORCEPROP 1 LAST PIN_NAMES_ROTATE TRUE
J 2
(-575 2350);
DISPLAY 0.489362 (-575 2350);
PAINT GREEN (-575 2350);
DISPLAY INVISIBLE (-575 2350);
FORCEPROP 2 LAST VOLTAGE 6.3V
J 2
(-925 2400);
DISPLAY 0.553191 (-925 2400);
DISPLAY INVISIBLE (-925 2400);
FORCEPROP 1 LAST MATERIAL X6S
J 2
(-566 2429);
DISPLAY 0.574468 (-566 2429);
PAINT GREEN (-566 2429);
DISPLAY INVISIBLE (-566 2429);
FORCEPROP 2 LAST PACK_TYPE C0201
J 2
(-750 2400);
DISPLAY 0.553191 (-750 2400);
DISPLAY INVISIBLE (-750 2400);
FORCEPROP 2 LAST TOLERANCE 20%
J 2
(-650 2400);
DISPLAY 0.553191 (-650 2400);
DISPLAY INVISIBLE (-650 2400);
FORCEPROP 1 LAST PART_NUMBER SP_CH4221MEE01
J 2
(-691 2438);
DISPLAY 0.574468 (-691 2438);
PAINT GREEN (-691 2438);
DISPLAY INVISIBLE (-691 2438);
FORCEPROP 1 LAST LOCATION C916
J 0
(-325 2425);
DISPLAY 1.021277 (-325 2425);
DISPLAY INVISIBLE (-325 2425);
FORCEPROP 1 LAST PATH I53
J 2
(-575 2350);
DISPLAY 0.723404 (-575 2350);
DISPLAY INVISIBLE (-575 2350);
FORCEADD Q_CAP_DIFFBUS..2
R 2
(-575 2300);
FORCEPROP 1 LAST LOCATION C917
J 2
(-341 2317);
DISPLAY 0.723404 (-341 2317);
PAINT GREEN (-341 2317);
FORCEPROP 2 LAST $SEC 1
J 2
(-400 2375);
DISPLAY 0.680851 (-400 2375);
PAINT MONO (-400 2375);
DISPLAY INVISIBLE (-400 2375);
FORCEPROP 2 LAST CDS_SEC 1
J 2
(-400 2375);
DISPLAY 0.680851 (-400 2375);
DISPLAY INVISIBLE (-400 2375);
FORCEPROP 2 LASTPIN (-500 2300) $PN 1
J 0
(-490 2310);
DISPLAY 0.808511 (-490 2310);
FORCEPROP 2 LASTPIN (-650 2300) $PN 2
J 2
(-660 2310);
DISPLAY 0.808511 (-660 2310);
FORCEPROP 2 LAST VALUE DIFF BUS_0.22UF
J 2
(-725 2300);
DISPLAY 0.553191 (-725 2300);
FORCEPROP 1 LAST CDS_LMAN_SYM_OUTLINE -25,50,25,-50
J 2
(-575 2300);
DISPLAY 0.468085 (-575 2300);
PAINT GREEN (-575 2300);
DISPLAY INVISIBLE (-575 2300);
FORCEPROP 2 LAST CDS_LIB pure_quanta
J 2
(-575 2300);
DISPLAY INVISIBLE (-575 2300);
FORCEPROP 1 LAST PIN_NAMES_ROTATE TRUE
J 2
(-575 2300);
DISPLAY 0.489362 (-575 2300);
PAINT GREEN (-575 2300);
DISPLAY INVISIBLE (-575 2300);
FORCEPROP 2 LAST VOLTAGE 6.3V
J 2
(-925 2350);
DISPLAY 0.553191 (-925 2350);
DISPLAY INVISIBLE (-925 2350);
FORCEPROP 1 LAST MATERIAL X6S
J 2
(-566 2379);
DISPLAY 0.574468 (-566 2379);
PAINT GREEN (-566 2379);
DISPLAY INVISIBLE (-566 2379);
FORCEPROP 2 LAST PACK_TYPE C0201
J 2
(-750 2350);
DISPLAY 0.553191 (-750 2350);
DISPLAY INVISIBLE (-750 2350);
FORCEPROP 2 LAST TOLERANCE 20%
J 2
(-650 2350);
DISPLAY 0.553191 (-650 2350);
DISPLAY INVISIBLE (-650 2350);
FORCEPROP 1 LAST PART_NUMBER SP_CH4221MEE01
J 2
(-691 2388);
DISPLAY 0.574468 (-691 2388);
PAINT GREEN (-691 2388);
DISPLAY INVISIBLE (-691 2388);
FORCEPROP 1 LAST LOCATION C917
J 0
(-325 2375);
DISPLAY 1.021277 (-325 2375);
DISPLAY INVISIBLE (-325 2375);
FORCEPROP 1 LAST PATH I54
J 2
(-575 2300);
DISPLAY 0.723404 (-575 2300);
DISPLAY INVISIBLE (-575 2300);
FORCEADD Q_CAP_DIFFBUS..2
R 2
(-575 2500);
FORCEPROP 1 LAST LOCATION C915
J 2
(-341 2517);
DISPLAY 0.723404 (-341 2517);
PAINT GREEN (-341 2517);
FORCEPROP 2 LAST $SEC 1
J 2
(-400 2575);
DISPLAY 0.680851 (-400 2575);
PAINT MONO (-400 2575);
DISPLAY INVISIBLE (-400 2575);
FORCEPROP 2 LAST CDS_SEC 1
J 2
(-400 2575);
DISPLAY 0.680851 (-400 2575);
DISPLAY INVISIBLE (-400 2575);
FORCEPROP 2 LASTPIN (-500 2500) $PN 1
J 0
(-490 2510);
DISPLAY 0.808511 (-490 2510);
FORCEPROP 2 LASTPIN (-650 2500) $PN 2
J 2
(-660 2510);
DISPLAY 0.808511 (-660 2510);
FORCEPROP 2 LAST VALUE DIFF BUS_0.22UF
J 2
(-725 2500);
DISPLAY 0.553191 (-725 2500);
FORCEPROP 1 LAST CDS_LMAN_SYM_OUTLINE -25,50,25,-50
J 2
(-575 2500);
DISPLAY 0.468085 (-575 2500);
PAINT GREEN (-575 2500);
DISPLAY INVISIBLE (-575 2500);
FORCEPROP 2 LAST CDS_LIB pure_quanta
J 2
(-575 2500);
DISPLAY INVISIBLE (-575 2500);
FORCEPROP 1 LAST PIN_NAMES_ROTATE TRUE
J 2
(-575 2500);
DISPLAY 0.489362 (-575 2500);
PAINT GREEN (-575 2500);
DISPLAY INVISIBLE (-575 2500);
FORCEPROP 2 LAST VOLTAGE 6.3V
J 2
(-925 2550);
DISPLAY 0.553191 (-925 2550);
DISPLAY INVISIBLE (-925 2550);
FORCEPROP 1 LAST MATERIAL X6S
J 2
(-566 2579);
DISPLAY 0.574468 (-566 2579);
PAINT GREEN (-566 2579);
DISPLAY INVISIBLE (-566 2579);
FORCEPROP 2 LAST PACK_TYPE C0201
J 2
(-750 2550);
DISPLAY 0.553191 (-750 2550);
DISPLAY INVISIBLE (-750 2550);
FORCEPROP 2 LAST TOLERANCE 20%
J 2
(-650 2550);
DISPLAY 0.553191 (-650 2550);
DISPLAY INVISIBLE (-650 2550);
FORCEPROP 1 LAST PART_NUMBER SP_CH4221MEE01
J 2
(-691 2588);
DISPLAY 0.574468 (-691 2588);
PAINT GREEN (-691 2588);
DISPLAY INVISIBLE (-691 2588);
FORCEPROP 1 LAST LOCATION C915
J 0
(-325 2575);
DISPLAY 1.021277 (-325 2575);
DISPLAY INVISIBLE (-325 2575);
FORCEPROP 1 LAST PATH I55
J 2
(-575 2500);
DISPLAY 0.723404 (-575 2500);
DISPLAY INVISIBLE (-575 2500);
FORCEADD Q_CAP_DIFFBUS..2
R 2
(-575 2550);
FORCEPROP 1 LAST LOCATION C914
J 2
(-341 2567);
DISPLAY 0.723404 (-341 2567);
PAINT GREEN (-341 2567);
FORCEPROP 2 LAST $SEC 1
J 2
(-400 2625);
DISPLAY 0.680851 (-400 2625);
PAINT MONO (-400 2625);
DISPLAY INVISIBLE (-400 2625);
FORCEPROP 2 LAST CDS_SEC 1
J 2
(-400 2625);
DISPLAY 0.680851 (-400 2625);
DISPLAY INVISIBLE (-400 2625);
FORCEPROP 2 LASTPIN (-500 2550) $PN 1
J 0
(-490 2560);
DISPLAY 0.808511 (-490 2560);
FORCEPROP 2 LASTPIN (-650 2550) $PN 2
J 2
(-660 2560);
DISPLAY 0.808511 (-660 2560);
FORCEPROP 2 LAST VALUE DIFF BUS_0.22UF
J 2
(-725 2550);
DISPLAY 0.553191 (-725 2550);
FORCEPROP 2 LAST CDS_LIB pure_quanta
J 2
(-575 2550);
DISPLAY INVISIBLE (-575 2550);
FORCEPROP 1 LAST CDS_LMAN_SYM_OUTLINE -25,50,25,-50
J 2
(-575 2550);
DISPLAY 0.468085 (-575 2550);
PAINT GREEN (-575 2550);
DISPLAY INVISIBLE (-575 2550);
FORCEPROP 1 LAST PIN_NAMES_ROTATE TRUE
J 2
(-575 2550);
DISPLAY 0.489362 (-575 2550);
PAINT GREEN (-575 2550);
DISPLAY INVISIBLE (-575 2550);
FORCEPROP 2 LAST VOLTAGE 6.3V
J 2
(-925 2600);
DISPLAY 0.553191 (-925 2600);
DISPLAY INVISIBLE (-925 2600);
FORCEPROP 1 LAST MATERIAL X6S
J 2
(-566 2629);
DISPLAY 0.574468 (-566 2629);
PAINT GREEN (-566 2629);
DISPLAY INVISIBLE (-566 2629);
FORCEPROP 2 LAST PACK_TYPE C0201
J 2
(-750 2600);
DISPLAY 0.553191 (-750 2600);
DISPLAY INVISIBLE (-750 2600);
FORCEPROP 2 LAST TOLERANCE 20%
J 2
(-650 2600);
DISPLAY 0.553191 (-650 2600);
DISPLAY INVISIBLE (-650 2600);
FORCEPROP 1 LAST PART_NUMBER SP_CH4221MEE01
J 2
(-691 2638);
DISPLAY 0.574468 (-691 2638);
PAINT GREEN (-691 2638);
DISPLAY INVISIBLE (-691 2638);
FORCEPROP 1 LAST LOCATION C914
J 0
(-325 2625);
DISPLAY 1.021277 (-325 2625);
DISPLAY INVISIBLE (-325 2625);
FORCEPROP 1 LAST PATH I56
J 2
(-575 2550);
DISPLAY 0.723404 (-575 2550);
DISPLAY INVISIBLE (-575 2550);
FORCEADD Q_CAP_DIFFBUS..2
R 2
(-575 2700);
FORCEPROP 1 LAST LOCATION C913
J 2
(-341 2717);
DISPLAY 0.723404 (-341 2717);
PAINT GREEN (-341 2717);
FORCEPROP 2 LAST $SEC 1
J 2
(-400 2775);
DISPLAY 0.680851 (-400 2775);
PAINT MONO (-400 2775);
DISPLAY INVISIBLE (-400 2775);
FORCEPROP 2 LAST CDS_SEC 1
J 2
(-400 2775);
DISPLAY 0.680851 (-400 2775);
DISPLAY INVISIBLE (-400 2775);
FORCEPROP 2 LASTPIN (-500 2700) $PN 1
J 0
(-490 2710);
DISPLAY 0.808511 (-490 2710);
FORCEPROP 2 LASTPIN (-650 2700) $PN 2
J 2
(-660 2710);
DISPLAY 0.808511 (-660 2710);
FORCEPROP 2 LAST VALUE DIFF BUS_0.22UF
J 2
(-725 2700);
DISPLAY 0.553191 (-725 2700);
FORCEPROP 1 LAST CDS_LMAN_SYM_OUTLINE -25,50,25,-50
J 2
(-575 2700);
DISPLAY 0.468085 (-575 2700);
PAINT GREEN (-575 2700);
DISPLAY INVISIBLE (-575 2700);
FORCEPROP 2 LAST CDS_LIB pure_quanta
J 2
(-575 2700);
DISPLAY INVISIBLE (-575 2700);
FORCEPROP 1 LAST PIN_NAMES_ROTATE TRUE
J 2
(-575 2700);
DISPLAY 0.489362 (-575 2700);
PAINT GREEN (-575 2700);
DISPLAY INVISIBLE (-575 2700);
FORCEPROP 2 LAST VOLTAGE 6.3V
J 2
(-925 2750);
DISPLAY 0.553191 (-925 2750);
DISPLAY INVISIBLE (-925 2750);
FORCEPROP 1 LAST MATERIAL X6S
J 2
(-566 2779);
DISPLAY 0.574468 (-566 2779);
PAINT GREEN (-566 2779);
DISPLAY INVISIBLE (-566 2779);
FORCEPROP 2 LAST PACK_TYPE C0201
J 2
(-750 2750);
DISPLAY 0.553191 (-750 2750);
DISPLAY INVISIBLE (-750 2750);
FORCEPROP 2 LAST TOLERANCE 20%
J 2
(-650 2750);
DISPLAY 0.553191 (-650 2750);
DISPLAY INVISIBLE (-650 2750);
FORCEPROP 1 LAST PART_NUMBER SP_CH4221MEE01
J 2
(-691 2788);
DISPLAY 0.574468 (-691 2788);
PAINT GREEN (-691 2788);
DISPLAY INVISIBLE (-691 2788);
FORCEPROP 1 LAST LOCATION C913
J 0
(-325 2775);
DISPLAY 1.021277 (-325 2775);
DISPLAY INVISIBLE (-325 2775);
FORCEPROP 1 LAST PATH I57
J 2
(-575 2700);
DISPLAY 0.723404 (-575 2700);
DISPLAY INVISIBLE (-575 2700);
FORCEADD Q_CAP_DIFFBUS..2
R 2
(-575 2750);
FORCEPROP 1 LAST LOCATION C912
J 2
(-341 2767);
DISPLAY 0.723404 (-341 2767);
PAINT GREEN (-341 2767);
FORCEPROP 2 LAST $SEC 1
J 2
(-400 2825);
DISPLAY 0.680851 (-400 2825);
PAINT MONO (-400 2825);
DISPLAY INVISIBLE (-400 2825);
FORCEPROP 2 LAST CDS_SEC 1
J 2
(-400 2825);
DISPLAY 0.680851 (-400 2825);
DISPLAY INVISIBLE (-400 2825);
FORCEPROP 2 LASTPIN (-500 2750) $PN 1
J 0
(-490 2760);
DISPLAY 0.808511 (-490 2760);
FORCEPROP 2 LASTPIN (-650 2750) $PN 2
J 2
(-660 2760);
DISPLAY 0.808511 (-660 2760);
FORCEPROP 2 LAST VALUE DIFF BUS_0.22UF
J 2
(-725 2750);
DISPLAY 0.553191 (-725 2750);
FORCEPROP 1 LAST CDS_LMAN_SYM_OUTLINE -25,50,25,-50
J 2
(-575 2750);
DISPLAY 0.468085 (-575 2750);
PAINT GREEN (-575 2750);
DISPLAY INVISIBLE (-575 2750);
FORCEPROP 2 LAST CDS_LIB pure_quanta
J 2
(-575 2750);
DISPLAY INVISIBLE (-575 2750);
FORCEPROP 1 LAST PIN_NAMES_ROTATE TRUE
J 2
(-575 2750);
DISPLAY 0.489362 (-575 2750);
PAINT GREEN (-575 2750);
DISPLAY INVISIBLE (-575 2750);
FORCEPROP 2 LAST VOLTAGE 6.3V
J 2
(-925 2800);
DISPLAY 0.553191 (-925 2800);
DISPLAY INVISIBLE (-925 2800);
FORCEPROP 1 LAST MATERIAL X6S
J 2
(-566 2829);
DISPLAY 0.574468 (-566 2829);
PAINT GREEN (-566 2829);
DISPLAY INVISIBLE (-566 2829);
FORCEPROP 2 LAST PACK_TYPE C0201
J 2
(-750 2800);
DISPLAY 0.553191 (-750 2800);
DISPLAY INVISIBLE (-750 2800);
FORCEPROP 2 LAST TOLERANCE 20%
J 2
(-650 2800);
DISPLAY 0.553191 (-650 2800);
DISPLAY INVISIBLE (-650 2800);
FORCEPROP 1 LAST PART_NUMBER SP_CH4221MEE01
J 2
(-691 2838);
DISPLAY 0.574468 (-691 2838);
PAINT GREEN (-691 2838);
DISPLAY INVISIBLE (-691 2838);
FORCEPROP 1 LAST LOCATION C912
J 0
(-325 2825);
DISPLAY 1.021277 (-325 2825);
DISPLAY INVISIBLE (-325 2825);
FORCEPROP 1 LAST PATH I58
J 2
(-575 2750);
DISPLAY 0.723404 (-575 2750);
DISPLAY INVISIBLE (-575 2750);
FORCEADD Q_CAP_DIFFBUS..2
R 2
(-575 2900);
FORCEPROP 1 LAST LOCATION C911
J 2
(-341 2917);
DISPLAY 0.723404 (-341 2917);
PAINT GREEN (-341 2917);
FORCEPROP 2 LAST $SEC 1
J 2
(-400 2975);
DISPLAY 0.680851 (-400 2975);
PAINT MONO (-400 2975);
DISPLAY INVISIBLE (-400 2975);
FORCEPROP 2 LAST CDS_SEC 1
J 2
(-400 2975);
DISPLAY 0.680851 (-400 2975);
DISPLAY INVISIBLE (-400 2975);
FORCEPROP 2 LASTPIN (-500 2900) $PN 1
J 0
(-490 2910);
DISPLAY 0.808511 (-490 2910);
FORCEPROP 2 LASTPIN (-650 2900) $PN 2
J 2
(-660 2910);
DISPLAY 0.808511 (-660 2910);
FORCEPROP 2 LAST VALUE DIFF BUS_0.22UF
J 2
(-725 2900);
DISPLAY 0.553191 (-725 2900);
FORCEPROP 2 LAST CDS_LIB pure_quanta
J 2
(-575 2900);
DISPLAY INVISIBLE (-575 2900);
FORCEPROP 1 LAST CDS_LMAN_SYM_OUTLINE -25,50,25,-50
J 2
(-575 2900);
DISPLAY 0.468085 (-575 2900);
PAINT GREEN (-575 2900);
DISPLAY INVISIBLE (-575 2900);
FORCEPROP 1 LAST PIN_NAMES_ROTATE TRUE
J 2
(-575 2900);
DISPLAY 0.489362 (-575 2900);
PAINT GREEN (-575 2900);
DISPLAY INVISIBLE (-575 2900);
FORCEPROP 2 LAST VOLTAGE 6.3V
J 2
(-925 2950);
DISPLAY 0.553191 (-925 2950);
DISPLAY INVISIBLE (-925 2950);
FORCEPROP 1 LAST MATERIAL X6S
J 2
(-566 2979);
DISPLAY 0.574468 (-566 2979);
PAINT GREEN (-566 2979);
DISPLAY INVISIBLE (-566 2979);
FORCEPROP 2 LAST PACK_TYPE C0201
J 2
(-750 2950);
DISPLAY 0.553191 (-750 2950);
DISPLAY INVISIBLE (-750 2950);
FORCEPROP 2 LAST TOLERANCE 20%
J 2
(-650 2950);
DISPLAY 0.553191 (-650 2950);
DISPLAY INVISIBLE (-650 2950);
FORCEPROP 1 LAST PART_NUMBER SP_CH4221MEE01
J 2
(-691 2988);
DISPLAY 0.574468 (-691 2988);
PAINT GREEN (-691 2988);
DISPLAY INVISIBLE (-691 2988);
FORCEPROP 1 LAST LOCATION C911
J 0
(-325 2975);
DISPLAY 1.021277 (-325 2975);
DISPLAY INVISIBLE (-325 2975);
FORCEPROP 1 LAST PATH I59
J 2
(-575 2900);
DISPLAY 0.723404 (-575 2900);
DISPLAY INVISIBLE (-575 2900);
FORCEADD TAP..1
R 2
(-1550 525);
FORCEPROP 3 LASTPIN (-1500 525) SIG_NAME P5E_CPU0_P0_TX_DP<1>
J 0
(-1490 535);
DISPLAY 0.659574 (-1490 535);
PAINT MONO (-1490 535);
DISPLAY INVISIBLE (-1490 535);
FORCEPROP 1 LASTPIN (-1500 525) BN 1
J 2
(-1488 533);
DISPLAY 0.680851 (-1488 533);
PAINT GREEN (-1488 533);
FORCEPROP 2 LAST CDS_LIB standard
J 0
(-1550 525);
DISPLAY INVISIBLE (-1550 525);
FORCEPROP 1 LAST BODY_TYPE PLUMBING
J 2
(-1550 575);
DISPLAY 0.872340 (-1550 575);
PAINT GREEN (-1550 575);
DISPLAY INVISIBLE (-1550 575);
FORCEPROP 1 LAST HDL_TAP TRUE
J 2
(-1875 400);
DISPLAY 0.872340 (-1875 400);
DISPLAY INVISIBLE (-1875 400);
FORCEPROP 1 LAST PATH I6
J 2
(-1548 525);
DISPLAY 0.872340 (-1548 525);
PAINT GREEN (-1548 525);
DISPLAY INVISIBLE (-1548 525);
FORCEADD Q_CAP_DIFFBUS..2
R 2
(-575 2950);
FORCEPROP 1 LAST LOCATION C910
J 2
(-341 2967);
DISPLAY 0.723404 (-341 2967);
PAINT GREEN (-341 2967);
FORCEPROP 2 LAST $SEC 1
J 2
(-400 3025);
DISPLAY 0.680851 (-400 3025);
PAINT MONO (-400 3025);
DISPLAY INVISIBLE (-400 3025);
FORCEPROP 2 LAST CDS_SEC 1
J 2
(-400 3025);
DISPLAY 0.680851 (-400 3025);
DISPLAY INVISIBLE (-400 3025);
FORCEPROP 2 LASTPIN (-500 2950) $PN 1
J 0
(-490 2960);
DISPLAY 0.808511 (-490 2960);
FORCEPROP 2 LASTPIN (-650 2950) $PN 2
J 2
(-660 2960);
DISPLAY 0.808511 (-660 2960);
FORCEPROP 2 LAST VALUE DIFF BUS_0.22UF
J 2
(-725 2950);
DISPLAY 0.553191 (-725 2950);
FORCEPROP 2 LAST CDS_LIB pure_quanta
J 2
(-575 2950);
DISPLAY INVISIBLE (-575 2950);
FORCEPROP 1 LAST CDS_LMAN_SYM_OUTLINE -25,50,25,-50
J 2
(-575 2950);
DISPLAY 0.468085 (-575 2950);
PAINT GREEN (-575 2950);
DISPLAY INVISIBLE (-575 2950);
FORCEPROP 1 LAST PIN_NAMES_ROTATE TRUE
J 2
(-575 2950);
DISPLAY 0.489362 (-575 2950);
PAINT GREEN (-575 2950);
DISPLAY INVISIBLE (-575 2950);
FORCEPROP 2 LAST VOLTAGE 6.3V
J 2
(-925 3000);
DISPLAY 0.553191 (-925 3000);
DISPLAY INVISIBLE (-925 3000);
FORCEPROP 1 LAST MATERIAL X6S
J 2
(-566 3029);
DISPLAY 0.574468 (-566 3029);
PAINT GREEN (-566 3029);
DISPLAY INVISIBLE (-566 3029);
FORCEPROP 2 LAST PACK_TYPE C0201
J 2
(-750 3000);
DISPLAY 0.553191 (-750 3000);
DISPLAY INVISIBLE (-750 3000);
FORCEPROP 2 LAST TOLERANCE 20%
J 2
(-650 3000);
DISPLAY 0.553191 (-650 3000);
DISPLAY INVISIBLE (-650 3000);
FORCEPROP 1 LAST PART_NUMBER SP_CH4221MEE01
J 2
(-691 3038);
DISPLAY 0.574468 (-691 3038);
PAINT GREEN (-691 3038);
DISPLAY INVISIBLE (-691 3038);
FORCEPROP 1 LAST LOCATION C910
J 0
(-325 3025);
DISPLAY 1.021277 (-325 3025);
DISPLAY INVISIBLE (-325 3025);
FORCEPROP 1 LAST PATH I60
J 2
(-575 2950);
DISPLAY 0.723404 (-575 2950);
DISPLAY INVISIBLE (-575 2950);
FORCEADD Q_CAP_DIFFBUS..2
R 2
(-575 3100);
FORCEPROP 1 LAST LOCATION C909
J 2
(-341 3117);
DISPLAY 0.723404 (-341 3117);
PAINT GREEN (-341 3117);
FORCEPROP 2 LAST $SEC 1
J 2
(-400 3175);
DISPLAY 0.680851 (-400 3175);
PAINT MONO (-400 3175);
DISPLAY INVISIBLE (-400 3175);
FORCEPROP 2 LAST CDS_SEC 1
J 2
(-400 3175);
DISPLAY 0.680851 (-400 3175);
DISPLAY INVISIBLE (-400 3175);
FORCEPROP 2 LASTPIN (-500 3100) $PN 1
J 0
(-490 3110);
DISPLAY 0.808511 (-490 3110);
FORCEPROP 2 LASTPIN (-650 3100) $PN 2
J 2
(-660 3110);
DISPLAY 0.808511 (-660 3110);
FORCEPROP 2 LAST VALUE DIFF BUS_0.22UF
J 2
(-725 3100);
DISPLAY 0.553191 (-725 3100);
FORCEPROP 1 LAST CDS_LMAN_SYM_OUTLINE -25,50,25,-50
J 2
(-575 3100);
DISPLAY 0.468085 (-575 3100);
PAINT GREEN (-575 3100);
DISPLAY INVISIBLE (-575 3100);
FORCEPROP 2 LAST CDS_LIB pure_quanta
J 2
(-575 3100);
DISPLAY INVISIBLE (-575 3100);
FORCEPROP 1 LAST PIN_NAMES_ROTATE TRUE
J 2
(-575 3100);
DISPLAY 0.489362 (-575 3100);
PAINT GREEN (-575 3100);
DISPLAY INVISIBLE (-575 3100);
FORCEPROP 2 LAST VOLTAGE 6.3V
J 2
(-925 3150);
DISPLAY 0.553191 (-925 3150);
DISPLAY INVISIBLE (-925 3150);
FORCEPROP 1 LAST MATERIAL X6S
J 2
(-566 3179);
DISPLAY 0.574468 (-566 3179);
PAINT GREEN (-566 3179);
DISPLAY INVISIBLE (-566 3179);
FORCEPROP 2 LAST PACK_TYPE C0201
J 2
(-750 3150);
DISPLAY 0.553191 (-750 3150);
DISPLAY INVISIBLE (-750 3150);
FORCEPROP 2 LAST TOLERANCE 20%
J 2
(-650 3150);
DISPLAY 0.553191 (-650 3150);
DISPLAY INVISIBLE (-650 3150);
FORCEPROP 1 LAST PART_NUMBER SP_CH4221MEE01
J 2
(-691 3188);
DISPLAY 0.574468 (-691 3188);
PAINT GREEN (-691 3188);
DISPLAY INVISIBLE (-691 3188);
FORCEPROP 1 LAST LOCATION C909
J 0
(-325 3175);
DISPLAY 1.021277 (-325 3175);
DISPLAY INVISIBLE (-325 3175);
FORCEPROP 1 LAST PATH I61
J 2
(-575 3100);
DISPLAY 0.723404 (-575 3100);
DISPLAY INVISIBLE (-575 3100);
FORCEADD Q_CAP_DIFFBUS..2
R 2
(-575 3150);
FORCEPROP 1 LAST LOCATION C908
J 2
(-341 3167);
DISPLAY 0.723404 (-341 3167);
PAINT GREEN (-341 3167);
FORCEPROP 2 LAST $SEC 1
J 2
(-400 3225);
DISPLAY 0.680851 (-400 3225);
PAINT MONO (-400 3225);
DISPLAY INVISIBLE (-400 3225);
FORCEPROP 2 LAST CDS_SEC 1
J 2
(-400 3225);
DISPLAY 0.680851 (-400 3225);
DISPLAY INVISIBLE (-400 3225);
FORCEPROP 2 LASTPIN (-500 3150) $PN 1
J 0
(-490 3160);
DISPLAY 0.808511 (-490 3160);
FORCEPROP 2 LASTPIN (-650 3150) $PN 2
J 2
(-660 3160);
DISPLAY 0.808511 (-660 3160);
FORCEPROP 2 LAST VALUE DIFF BUS_0.22UF
J 2
(-725 3150);
DISPLAY 0.553191 (-725 3150);
FORCEPROP 1 LAST CDS_LMAN_SYM_OUTLINE -25,50,25,-50
J 2
(-575 3150);
DISPLAY 0.468085 (-575 3150);
PAINT GREEN (-575 3150);
DISPLAY INVISIBLE (-575 3150);
FORCEPROP 2 LAST CDS_LIB pure_quanta
J 2
(-575 3150);
DISPLAY INVISIBLE (-575 3150);
FORCEPROP 1 LAST PIN_NAMES_ROTATE TRUE
J 2
(-575 3150);
DISPLAY 0.489362 (-575 3150);
PAINT GREEN (-575 3150);
DISPLAY INVISIBLE (-575 3150);
FORCEPROP 2 LAST VOLTAGE 6.3V
J 2
(-925 3200);
DISPLAY 0.553191 (-925 3200);
DISPLAY INVISIBLE (-925 3200);
FORCEPROP 1 LAST MATERIAL X6S
J 2
(-566 3229);
DISPLAY 0.574468 (-566 3229);
PAINT GREEN (-566 3229);
DISPLAY INVISIBLE (-566 3229);
FORCEPROP 2 LAST PACK_TYPE C0201
J 2
(-750 3200);
DISPLAY 0.553191 (-750 3200);
DISPLAY INVISIBLE (-750 3200);
FORCEPROP 2 LAST TOLERANCE 20%
J 2
(-650 3200);
DISPLAY 0.553191 (-650 3200);
DISPLAY INVISIBLE (-650 3200);
FORCEPROP 1 LAST PART_NUMBER SP_CH4221MEE01
J 2
(-691 3238);
DISPLAY 0.574468 (-691 3238);
PAINT GREEN (-691 3238);
DISPLAY INVISIBLE (-691 3238);
FORCEPROP 1 LAST LOCATION C908
J 0
(-325 3225);
DISPLAY 1.021277 (-325 3225);
DISPLAY INVISIBLE (-325 3225);
FORCEPROP 1 LAST PATH I62
J 2
(-575 3150);
DISPLAY 0.723404 (-575 3150);
DISPLAY INVISIBLE (-575 3150);
FORCEADD Q_CAP_DIFFBUS..2
R 2
(-575 3350);
FORCEPROP 1 LAST LOCATION C906
J 2
(-341 3367);
DISPLAY 0.723404 (-341 3367);
PAINT GREEN (-341 3367);
FORCEPROP 2 LAST $SEC 1
J 2
(-400 3425);
DISPLAY 0.680851 (-400 3425);
PAINT MONO (-400 3425);
DISPLAY INVISIBLE (-400 3425);
FORCEPROP 2 LAST CDS_SEC 1
J 2
(-400 3425);
DISPLAY 0.680851 (-400 3425);
DISPLAY INVISIBLE (-400 3425);
FORCEPROP 2 LASTPIN (-500 3350) $PN 1
J 0
(-490 3360);
DISPLAY 0.808511 (-490 3360);
FORCEPROP 2 LASTPIN (-650 3350) $PN 2
J 2
(-660 3360);
DISPLAY 0.808511 (-660 3360);
FORCEPROP 2 LAST VALUE DIFF BUS_0.22UF
J 2
(-725 3350);
DISPLAY 0.553191 (-725 3350);
FORCEPROP 1 LAST CDS_LMAN_SYM_OUTLINE -25,50,25,-50
J 2
(-575 3350);
DISPLAY 0.468085 (-575 3350);
PAINT GREEN (-575 3350);
DISPLAY INVISIBLE (-575 3350);
FORCEPROP 2 LAST CDS_LIB pure_quanta
J 2
(-575 3350);
DISPLAY INVISIBLE (-575 3350);
FORCEPROP 1 LAST PIN_NAMES_ROTATE TRUE
J 2
(-575 3350);
DISPLAY 0.489362 (-575 3350);
PAINT GREEN (-575 3350);
DISPLAY INVISIBLE (-575 3350);
FORCEPROP 2 LAST VOLTAGE 6.3V
J 2
(-925 3400);
DISPLAY 0.553191 (-925 3400);
DISPLAY INVISIBLE (-925 3400);
FORCEPROP 1 LAST MATERIAL X6S
J 2
(-566 3429);
DISPLAY 0.574468 (-566 3429);
PAINT GREEN (-566 3429);
DISPLAY INVISIBLE (-566 3429);
FORCEPROP 2 LAST PACK_TYPE C0201
J 2
(-750 3400);
DISPLAY 0.553191 (-750 3400);
DISPLAY INVISIBLE (-750 3400);
FORCEPROP 2 LAST TOLERANCE 20%
J 2
(-650 3400);
DISPLAY 0.553191 (-650 3400);
DISPLAY INVISIBLE (-650 3400);
FORCEPROP 1 LAST PART_NUMBER SP_CH4221MEE01
J 2
(-691 3438);
DISPLAY 0.574468 (-691 3438);
PAINT GREEN (-691 3438);
DISPLAY INVISIBLE (-691 3438);
FORCEPROP 1 LAST LOCATION C906
J 0
(-325 3425);
DISPLAY 1.021277 (-325 3425);
DISPLAY INVISIBLE (-325 3425);
FORCEPROP 1 LAST PATH I63
J 2
(-575 3350);
DISPLAY 0.723404 (-575 3350);
DISPLAY INVISIBLE (-575 3350);
FORCEADD Q_CAP_DIFFBUS..2
R 2
(-575 3300);
FORCEPROP 1 LAST LOCATION C907
J 2
(-341 3317);
DISPLAY 0.723404 (-341 3317);
PAINT GREEN (-341 3317);
FORCEPROP 2 LAST $SEC 1
J 2
(-400 3375);
DISPLAY 0.680851 (-400 3375);
PAINT MONO (-400 3375);
DISPLAY INVISIBLE (-400 3375);
FORCEPROP 2 LAST CDS_SEC 1
J 2
(-400 3375);
DISPLAY 0.680851 (-400 3375);
DISPLAY INVISIBLE (-400 3375);
FORCEPROP 2 LASTPIN (-500 3300) $PN 1
J 0
(-490 3310);
DISPLAY 0.808511 (-490 3310);
FORCEPROP 2 LASTPIN (-650 3300) $PN 2
J 2
(-660 3310);
DISPLAY 0.808511 (-660 3310);
FORCEPROP 2 LAST VALUE DIFF BUS_0.22UF
J 2
(-725 3300);
DISPLAY 0.553191 (-725 3300);
FORCEPROP 1 LAST CDS_LMAN_SYM_OUTLINE -25,50,25,-50
J 2
(-575 3300);
DISPLAY 0.468085 (-575 3300);
PAINT GREEN (-575 3300);
DISPLAY INVISIBLE (-575 3300);
FORCEPROP 2 LAST CDS_LIB pure_quanta
J 2
(-575 3300);
DISPLAY INVISIBLE (-575 3300);
FORCEPROP 1 LAST PIN_NAMES_ROTATE TRUE
J 2
(-575 3300);
DISPLAY 0.489362 (-575 3300);
PAINT GREEN (-575 3300);
DISPLAY INVISIBLE (-575 3300);
FORCEPROP 2 LAST VOLTAGE 6.3V
J 2
(-925 3350);
DISPLAY 0.553191 (-925 3350);
DISPLAY INVISIBLE (-925 3350);
FORCEPROP 1 LAST MATERIAL X6S
J 2
(-566 3379);
DISPLAY 0.574468 (-566 3379);
PAINT GREEN (-566 3379);
DISPLAY INVISIBLE (-566 3379);
FORCEPROP 2 LAST PACK_TYPE C0201
J 2
(-750 3350);
DISPLAY 0.553191 (-750 3350);
DISPLAY INVISIBLE (-750 3350);
FORCEPROP 2 LAST TOLERANCE 20%
J 2
(-650 3350);
DISPLAY 0.553191 (-650 3350);
DISPLAY INVISIBLE (-650 3350);
FORCEPROP 1 LAST PART_NUMBER SP_CH4221MEE01
J 2
(-691 3388);
DISPLAY 0.574468 (-691 3388);
PAINT GREEN (-691 3388);
DISPLAY INVISIBLE (-691 3388);
FORCEPROP 1 LAST LOCATION C907
J 0
(-325 3375);
DISPLAY 1.021277 (-325 3375);
DISPLAY INVISIBLE (-325 3375);
FORCEPROP 1 LAST PATH I64
J 2
(-575 3300);
DISPLAY 0.723404 (-575 3300);
DISPLAY INVISIBLE (-575 3300);
FORCEADD Q_CAP_DIFFBUS..2
R 2
(-575 3500);
FORCEPROP 1 LAST LOCATION C905
J 2
(-341 3517);
DISPLAY 0.723404 (-341 3517);
PAINT GREEN (-341 3517);
FORCEPROP 2 LAST $SEC 1
J 2
(-400 3575);
DISPLAY 0.680851 (-400 3575);
PAINT MONO (-400 3575);
DISPLAY INVISIBLE (-400 3575);
FORCEPROP 2 LAST CDS_SEC 1
J 2
(-400 3575);
DISPLAY 0.680851 (-400 3575);
DISPLAY INVISIBLE (-400 3575);
FORCEPROP 2 LASTPIN (-500 3500) $PN 1
J 0
(-490 3510);
DISPLAY 0.808511 (-490 3510);
FORCEPROP 2 LASTPIN (-650 3500) $PN 2
J 2
(-660 3510);
DISPLAY 0.808511 (-660 3510);
FORCEPROP 2 LAST VALUE DIFF BUS_0.22UF
J 2
(-725 3500);
DISPLAY 0.553191 (-725 3500);
FORCEPROP 1 LAST CDS_LMAN_SYM_OUTLINE -25,50,25,-50
J 2
(-575 3500);
DISPLAY 0.468085 (-575 3500);
PAINT GREEN (-575 3500);
DISPLAY INVISIBLE (-575 3500);
FORCEPROP 2 LAST CDS_LIB pure_quanta
J 2
(-575 3500);
DISPLAY INVISIBLE (-575 3500);
FORCEPROP 1 LAST PIN_NAMES_ROTATE TRUE
J 2
(-575 3500);
DISPLAY 0.489362 (-575 3500);
PAINT GREEN (-575 3500);
DISPLAY INVISIBLE (-575 3500);
FORCEPROP 2 LAST VOLTAGE 6.3V
J 2
(-925 3550);
DISPLAY 0.553191 (-925 3550);
DISPLAY INVISIBLE (-925 3550);
FORCEPROP 1 LAST MATERIAL X6S
J 2
(-566 3579);
DISPLAY 0.574468 (-566 3579);
PAINT GREEN (-566 3579);
DISPLAY INVISIBLE (-566 3579);
FORCEPROP 2 LAST PACK_TYPE C0201
J 2
(-750 3550);
DISPLAY 0.553191 (-750 3550);
DISPLAY INVISIBLE (-750 3550);
FORCEPROP 2 LAST TOLERANCE 20%
J 2
(-650 3550);
DISPLAY 0.553191 (-650 3550);
DISPLAY INVISIBLE (-650 3550);
FORCEPROP 1 LAST PART_NUMBER SP_CH4221MEE01
J 2
(-691 3588);
DISPLAY 0.574468 (-691 3588);
PAINT GREEN (-691 3588);
DISPLAY INVISIBLE (-691 3588);
FORCEPROP 1 LAST LOCATION C905
J 0
(-325 3575);
DISPLAY 1.021277 (-325 3575);
DISPLAY INVISIBLE (-325 3575);
FORCEPROP 1 LAST PATH I65
J 2
(-575 3500);
DISPLAY 0.723404 (-575 3500);
DISPLAY INVISIBLE (-575 3500);
FORCEADD Q_CAP_DIFFBUS..2
R 2
(-575 3550);
FORCEPROP 1 LAST LOCATION C904
J 2
(-341 3567);
DISPLAY 0.723404 (-341 3567);
PAINT GREEN (-341 3567);
FORCEPROP 2 LAST $SEC 1
J 2
(-400 3625);
DISPLAY 0.680851 (-400 3625);
PAINT MONO (-400 3625);
DISPLAY INVISIBLE (-400 3625);
FORCEPROP 2 LAST CDS_SEC 1
J 2
(-400 3625);
DISPLAY 0.680851 (-400 3625);
DISPLAY INVISIBLE (-400 3625);
FORCEPROP 2 LASTPIN (-500 3550) $PN 1
J 0
(-490 3560);
DISPLAY 0.808511 (-490 3560);
FORCEPROP 2 LASTPIN (-650 3550) $PN 2
J 2
(-660 3560);
DISPLAY 0.808511 (-660 3560);
FORCEPROP 2 LAST VALUE DIFF BUS_0.22UF
J 2
(-725 3550);
DISPLAY 0.553191 (-725 3550);
FORCEPROP 1 LAST CDS_LMAN_SYM_OUTLINE -25,50,25,-50
J 2
(-575 3550);
DISPLAY 0.468085 (-575 3550);
PAINT GREEN (-575 3550);
DISPLAY INVISIBLE (-575 3550);
FORCEPROP 2 LAST CDS_LIB pure_quanta
J 2
(-575 3550);
DISPLAY INVISIBLE (-575 3550);
FORCEPROP 1 LAST PIN_NAMES_ROTATE TRUE
J 2
(-575 3550);
DISPLAY 0.489362 (-575 3550);
PAINT GREEN (-575 3550);
DISPLAY INVISIBLE (-575 3550);
FORCEPROP 2 LAST VOLTAGE 6.3V
J 2
(-925 3600);
DISPLAY 0.553191 (-925 3600);
DISPLAY INVISIBLE (-925 3600);
FORCEPROP 1 LAST MATERIAL X6S
J 2
(-566 3629);
DISPLAY 0.574468 (-566 3629);
PAINT GREEN (-566 3629);
DISPLAY INVISIBLE (-566 3629);
FORCEPROP 2 LAST PACK_TYPE C0201
J 2
(-750 3600);
DISPLAY 0.553191 (-750 3600);
DISPLAY INVISIBLE (-750 3600);
FORCEPROP 2 LAST TOLERANCE 20%
J 2
(-650 3600);
DISPLAY 0.553191 (-650 3600);
DISPLAY INVISIBLE (-650 3600);
FORCEPROP 1 LAST PART_NUMBER SP_CH4221MEE01
J 2
(-691 3638);
DISPLAY 0.574468 (-691 3638);
PAINT GREEN (-691 3638);
DISPLAY INVISIBLE (-691 3638);
FORCEPROP 1 LAST LOCATION C904
J 0
(-325 3625);
DISPLAY 1.021277 (-325 3625);
DISPLAY INVISIBLE (-325 3625);
FORCEPROP 1 LAST PATH I66
J 2
(-575 3550);
DISPLAY 0.723404 (-575 3550);
DISPLAY INVISIBLE (-575 3550);
FORCEADD Q_CAP_DIFFBUS..2
R 2
(-575 3700);
FORCEPROP 1 LAST LOCATION C903
J 2
(-341 3717);
DISPLAY 0.723404 (-341 3717);
PAINT GREEN (-341 3717);
FORCEPROP 2 LAST $SEC 1
J 2
(-400 3775);
DISPLAY 0.680851 (-400 3775);
PAINT MONO (-400 3775);
DISPLAY INVISIBLE (-400 3775);
FORCEPROP 2 LAST CDS_SEC 1
J 2
(-400 3775);
DISPLAY 0.680851 (-400 3775);
DISPLAY INVISIBLE (-400 3775);
FORCEPROP 2 LASTPIN (-500 3700) $PN 1
J 0
(-490 3710);
DISPLAY 0.808511 (-490 3710);
FORCEPROP 2 LASTPIN (-650 3700) $PN 2
J 2
(-660 3710);
DISPLAY 0.808511 (-660 3710);
FORCEPROP 2 LAST VALUE DIFF BUS_0.22UF
J 2
(-725 3700);
DISPLAY 0.553191 (-725 3700);
FORCEPROP 1 LAST CDS_LMAN_SYM_OUTLINE -25,50,25,-50
J 2
(-575 3700);
DISPLAY 0.468085 (-575 3700);
PAINT GREEN (-575 3700);
DISPLAY INVISIBLE (-575 3700);
FORCEPROP 2 LAST CDS_LIB pure_quanta
J 2
(-575 3700);
DISPLAY INVISIBLE (-575 3700);
FORCEPROP 1 LAST PIN_NAMES_ROTATE TRUE
J 2
(-575 3700);
DISPLAY 0.489362 (-575 3700);
PAINT GREEN (-575 3700);
DISPLAY INVISIBLE (-575 3700);
FORCEPROP 2 LAST VOLTAGE 6.3V
J 2
(-925 3750);
DISPLAY 0.553191 (-925 3750);
DISPLAY INVISIBLE (-925 3750);
FORCEPROP 1 LAST MATERIAL X6S
J 2
(-566 3779);
DISPLAY 0.574468 (-566 3779);
PAINT GREEN (-566 3779);
DISPLAY INVISIBLE (-566 3779);
FORCEPROP 2 LAST PACK_TYPE C0201
J 2
(-750 3750);
DISPLAY 0.553191 (-750 3750);
DISPLAY INVISIBLE (-750 3750);
FORCEPROP 2 LAST TOLERANCE 20%
J 2
(-650 3750);
DISPLAY 0.553191 (-650 3750);
DISPLAY INVISIBLE (-650 3750);
FORCEPROP 1 LAST PART_NUMBER SP_CH4221MEE01
J 2
(-691 3788);
DISPLAY 0.574468 (-691 3788);
PAINT GREEN (-691 3788);
DISPLAY INVISIBLE (-691 3788);
FORCEPROP 1 LAST LOCATION C903
J 0
(-325 3775);
DISPLAY 1.021277 (-325 3775);
DISPLAY INVISIBLE (-325 3775);
FORCEPROP 1 LAST PATH I67
J 2
(-575 3700);
DISPLAY 0.723404 (-575 3700);
DISPLAY INVISIBLE (-575 3700);
FORCEADD Q_CAP_DIFFBUS..2
R 2
(-575 3750);
FORCEPROP 1 LAST LOCATION C902
J 2
(-341 3767);
DISPLAY 0.723404 (-341 3767);
PAINT GREEN (-341 3767);
FORCEPROP 2 LAST $SEC 1
J 2
(-400 3825);
DISPLAY 0.680851 (-400 3825);
PAINT MONO (-400 3825);
DISPLAY INVISIBLE (-400 3825);
FORCEPROP 2 LAST CDS_SEC 1
J 2
(-400 3825);
DISPLAY 0.680851 (-400 3825);
DISPLAY INVISIBLE (-400 3825);
FORCEPROP 2 LASTPIN (-500 3750) $PN 1
J 0
(-490 3760);
DISPLAY 0.808511 (-490 3760);
FORCEPROP 2 LASTPIN (-650 3750) $PN 2
J 2
(-660 3760);
DISPLAY 0.808511 (-660 3760);
FORCEPROP 1 LAST MATERIAL X6S
J 2
(-666 3954);
DISPLAY 0.574468 (-666 3954);
PAINT GREEN (-666 3954);
FORCEPROP 2 LAST TOLERANCE 20%
J 2
(-525 3900);
DISPLAY 0.553191 (-525 3900);
PAINT GREEN (-525 3900);
FORCEPROP 2 LAST VOLTAGE 6.3V
J 2
(-400 3900);
DISPLAY 0.553191 (-400 3900);
PAINT GREEN (-400 3900);
FORCEPROP 2 LAST PACK_TYPE C0201
J 2
(-625 3900);
DISPLAY 0.553191 (-625 3900);
PAINT GREEN (-625 3900);
FORCEPROP 2 LAST VALUE DIFF BUS_0.22UF
J 2
(-725 3750);
DISPLAY 0.553191 (-725 3750);
FORCEPROP 2 LAST CDS_LIB pure_quanta
J 2
(-575 3750);
DISPLAY INVISIBLE (-575 3750);
FORCEPROP 1 LAST CDS_LMAN_SYM_OUTLINE -25,50,25,-50
J 2
(-575 3750);
DISPLAY 0.468085 (-575 3750);
PAINT GREEN (-575 3750);
DISPLAY INVISIBLE (-575 3750);
FORCEPROP 1 LAST PIN_NAMES_ROTATE TRUE
J 2
(-575 3750);
DISPLAY 0.489362 (-575 3750);
PAINT GREEN (-575 3750);
DISPLAY INVISIBLE (-575 3750);
FORCEPROP 1 LAST PART_NUMBER SP_CH4221MEE01
J 2
(-391 3838);
DISPLAY 0.574468 (-391 3838);
PAINT GREEN (-391 3838);
DISPLAY INVISIBLE (-391 3838);
FORCEPROP 1 LAST LOCATION C902
J 0
(-325 3825);
DISPLAY 1.021277 (-325 3825);
DISPLAY INVISIBLE (-325 3825);
FORCEPROP 1 LAST PATH I68
J 2
(-575 3750);
DISPLAY 0.723404 (-575 3750);
DISPLAY INVISIBLE (-575 3750);
FORCEADD TAP..1
(-25 3550);
FORCEPROP 3 LASTPIN (-75 3550) SIG_NAME P5E_CPU0_P0_TX_C_DN<14>
J 0
(-65 3560);
DISPLAY 0.659574 (-65 3560);
PAINT MONO (-65 3560);
DISPLAY INVISIBLE (-65 3560);
FORCEPROP 1 LASTPIN (-75 3550) BN 14
J 0
(-87 3558);
DISPLAY 0.680851 (-87 3558);
PAINT GREEN (-87 3558);
FORCEPROP 2 LAST CDS_LIB standard
J 0
(-25 3550);
DISPLAY INVISIBLE (-25 3550);
FORCEPROP 1 LAST BODY_TYPE PLUMBING
J 0
(-25 3600);
DISPLAY 0.872340 (-25 3600);
PAINT GREEN (-25 3600);
DISPLAY INVISIBLE (-25 3600);
FORCEPROP 1 LAST HDL_TAP TRUE
J 0
(300 3425);
DISPLAY 0.872340 (300 3425);
DISPLAY INVISIBLE (300 3425);
FORCEPROP 1 LAST PATH I69
J 0
(-27 3550);
DISPLAY 0.872340 (-27 3550);
PAINT GREEN (-27 3550);
DISPLAY INVISIBLE (-27 3550);
FORCEADD TAP..1
R 2
(-1300 375);
FORCEPROP 3 LASTPIN (-1250 375) SIG_NAME P5E_CPU0_P0_TX_DN<0>
J 0
(-1240 385);
DISPLAY 0.659574 (-1240 385);
PAINT MONO (-1240 385);
DISPLAY INVISIBLE (-1240 385);
FORCEPROP 1 LASTPIN (-1250 375) BN 0
J 2
(-1238 383);
DISPLAY 0.680851 (-1238 383);
PAINT GREEN (-1238 383);
FORCEPROP 2 LAST CDS_LIB standard
J 0
(-1300 375);
DISPLAY INVISIBLE (-1300 375);
FORCEPROP 1 LAST BODY_TYPE PLUMBING
J 2
(-1300 425);
DISPLAY 0.872340 (-1300 425);
PAINT GREEN (-1300 425);
DISPLAY INVISIBLE (-1300 425);
FORCEPROP 1 LAST HDL_TAP TRUE
J 2
(-1625 250);
DISPLAY 0.872340 (-1625 250);
DISPLAY INVISIBLE (-1625 250);
FORCEPROP 1 LAST PATH I7
J 2
(-1298 375);
DISPLAY 0.872340 (-1298 375);
PAINT GREEN (-1298 375);
DISPLAY INVISIBLE (-1298 375);
FORCEADD TAP..1
(-25 2950);
FORCEPROP 3 LASTPIN (-75 2950) SIG_NAME P5E_CPU0_P0_TX_C_DN<11>
J 0
(-65 2960);
DISPLAY 0.659574 (-65 2960);
PAINT MONO (-65 2960);
DISPLAY INVISIBLE (-65 2960);
FORCEPROP 1 LASTPIN (-75 2950) BN 11
J 0
(-87 2958);
DISPLAY 0.680851 (-87 2958);
PAINT GREEN (-87 2958);
FORCEPROP 2 LAST CDS_LIB standard
J 0
(-25 2950);
DISPLAY INVISIBLE (-25 2950);
FORCEPROP 1 LAST BODY_TYPE PLUMBING
J 0
(-25 3000);
DISPLAY 0.872340 (-25 3000);
PAINT GREEN (-25 3000);
DISPLAY INVISIBLE (-25 3000);
FORCEPROP 1 LAST HDL_TAP TRUE
J 0
(300 2825);
DISPLAY 0.872340 (300 2825);
DISPLAY INVISIBLE (300 2825);
FORCEPROP 1 LAST PATH I70
J 0
(-27 2950);
DISPLAY 0.872340 (-27 2950);
PAINT GREEN (-27 2950);
DISPLAY INVISIBLE (-27 2950);
FORCEADD TAP..1
(-25 3350);
FORCEPROP 3 LASTPIN (-75 3350) SIG_NAME P5E_CPU0_P0_TX_C_DN<13>
J 0
(-65 3360);
DISPLAY 0.659574 (-65 3360);
PAINT MONO (-65 3360);
DISPLAY INVISIBLE (-65 3360);
FORCEPROP 1 LASTPIN (-75 3350) BN 13
J 0
(-87 3358);
DISPLAY 0.680851 (-87 3358);
PAINT GREEN (-87 3358);
FORCEPROP 2 LAST CDS_LIB standard
J 0
(-25 3350);
DISPLAY INVISIBLE (-25 3350);
FORCEPROP 1 LAST BODY_TYPE PLUMBING
J 0
(-25 3400);
DISPLAY 0.872340 (-25 3400);
PAINT GREEN (-25 3400);
DISPLAY INVISIBLE (-25 3400);
FORCEPROP 1 LAST HDL_TAP TRUE
J 0
(300 3225);
DISPLAY 0.872340 (300 3225);
DISPLAY INVISIBLE (300 3225);
FORCEPROP 1 LAST PATH I71
J 0
(-27 3350);
DISPLAY 0.872340 (-27 3350);
PAINT GREEN (-27 3350);
DISPLAY INVISIBLE (-27 3350);
FORCEADD TAP..1
(-25 3150);
FORCEPROP 3 LASTPIN (-75 3150) SIG_NAME P5E_CPU0_P0_TX_C_DN<12>
J 0
(-65 3160);
DISPLAY 0.659574 (-65 3160);
PAINT MONO (-65 3160);
DISPLAY INVISIBLE (-65 3160);
FORCEPROP 1 LASTPIN (-75 3150) BN 12
J 0
(-87 3158);
DISPLAY 0.680851 (-87 3158);
PAINT GREEN (-87 3158);
FORCEPROP 2 LAST CDS_LIB standard
J 0
(-25 3150);
DISPLAY INVISIBLE (-25 3150);
FORCEPROP 1 LAST BODY_TYPE PLUMBING
J 0
(-25 3200);
DISPLAY 0.872340 (-25 3200);
PAINT GREEN (-25 3200);
DISPLAY INVISIBLE (-25 3200);
FORCEPROP 1 LAST HDL_TAP TRUE
J 0
(300 3025);
DISPLAY 0.872340 (300 3025);
DISPLAY INVISIBLE (300 3025);
FORCEPROP 1 LAST PATH I72
J 0
(-27 3150);
DISPLAY 0.872340 (-27 3150);
PAINT GREEN (-27 3150);
DISPLAY INVISIBLE (-27 3150);
FORCEADD TAP..1
(-25 2750);
FORCEPROP 3 LASTPIN (-75 2750) SIG_NAME P5E_CPU0_P0_TX_C_DN<10>
J 0
(-65 2760);
DISPLAY 0.659574 (-65 2760);
PAINT MONO (-65 2760);
DISPLAY INVISIBLE (-65 2760);
FORCEPROP 1 LASTPIN (-75 2750) BN 10
J 0
(-87 2758);
DISPLAY 0.680851 (-87 2758);
PAINT GREEN (-87 2758);
FORCEPROP 2 LAST CDS_LIB standard
J 0
(-25 2750);
DISPLAY INVISIBLE (-25 2750);
FORCEPROP 1 LAST BODY_TYPE PLUMBING
J 0
(-25 2800);
DISPLAY 0.872340 (-25 2800);
PAINT GREEN (-25 2800);
DISPLAY INVISIBLE (-25 2800);
FORCEPROP 1 LAST HDL_TAP TRUE
J 0
(300 2625);
DISPLAY 0.872340 (300 2625);
DISPLAY INVISIBLE (300 2625);
FORCEPROP 1 LAST PATH I73
J 0
(-27 2750);
DISPLAY 0.872340 (-27 2750);
PAINT GREEN (-27 2750);
DISPLAY INVISIBLE (-27 2750);
FORCEADD TAP..1
(-25 2350);
FORCEPROP 3 LASTPIN (-75 2350) SIG_NAME P5E_CPU0_P0_TX_C_DN<8>
J 0
(-65 2360);
DISPLAY 0.659574 (-65 2360);
PAINT MONO (-65 2360);
DISPLAY INVISIBLE (-65 2360);
FORCEPROP 1 LASTPIN (-75 2350) BN 8
J 0
(-87 2358);
DISPLAY 0.680851 (-87 2358);
PAINT GREEN (-87 2358);
FORCEPROP 2 LAST CDS_LIB standard
J 0
(-25 2350);
DISPLAY INVISIBLE (-25 2350);
FORCEPROP 1 LAST BODY_TYPE PLUMBING
J 0
(-25 2400);
DISPLAY 0.872340 (-25 2400);
PAINT GREEN (-25 2400);
DISPLAY INVISIBLE (-25 2400);
FORCEPROP 1 LAST HDL_TAP TRUE
J 0
(300 2225);
DISPLAY 0.872340 (300 2225);
DISPLAY INVISIBLE (300 2225);
FORCEPROP 1 LAST PATH I74
J 0
(-27 2350);
DISPLAY 0.872340 (-27 2350);
PAINT GREEN (-27 2350);
DISPLAY INVISIBLE (-27 2350);
FORCEADD TAP..1
(-25 2550);
FORCEPROP 3 LASTPIN (-75 2550) SIG_NAME P5E_CPU0_P0_TX_C_DN<9>
J 0
(-65 2560);
DISPLAY 0.659574 (-65 2560);
PAINT MONO (-65 2560);
DISPLAY INVISIBLE (-65 2560);
FORCEPROP 1 LASTPIN (-75 2550) BN 9
J 0
(-87 2558);
DISPLAY 0.680851 (-87 2558);
PAINT GREEN (-87 2558);
FORCEPROP 2 LAST CDS_LIB standard
J 0
(-25 2550);
DISPLAY INVISIBLE (-25 2550);
FORCEPROP 1 LAST BODY_TYPE PLUMBING
J 0
(-25 2600);
DISPLAY 0.872340 (-25 2600);
PAINT GREEN (-25 2600);
DISPLAY INVISIBLE (-25 2600);
FORCEPROP 1 LAST HDL_TAP TRUE
J 0
(300 2425);
DISPLAY 0.872340 (300 2425);
DISPLAY INVISIBLE (300 2425);
FORCEPROP 1 LAST PATH I75
J 0
(-27 2550);
DISPLAY 0.872340 (-27 2550);
PAINT GREEN (-27 2550);
DISPLAY INVISIBLE (-27 2550);
FORCEADD TAP..1
(-25 1775);
FORCEPROP 3 LASTPIN (-75 1775) SIG_NAME P5E_CPU0_P0_TX_C_DN<7>
J 0
(-65 1785);
DISPLAY 0.659574 (-65 1785);
PAINT MONO (-65 1785);
DISPLAY INVISIBLE (-65 1785);
FORCEPROP 1 LASTPIN (-75 1775) BN 7
J 0
(-87 1783);
DISPLAY 0.680851 (-87 1783);
PAINT GREEN (-87 1783);
FORCEPROP 2 LAST CDS_LIB standard
J 0
(-25 1775);
DISPLAY INVISIBLE (-25 1775);
FORCEPROP 1 LAST BODY_TYPE PLUMBING
J 0
(-25 1825);
DISPLAY 0.872340 (-25 1825);
PAINT GREEN (-25 1825);
DISPLAY INVISIBLE (-25 1825);
FORCEPROP 1 LAST HDL_TAP TRUE
J 0
(300 1650);
DISPLAY 0.872340 (300 1650);
DISPLAY INVISIBLE (300 1650);
FORCEPROP 1 LAST PATH I76
J 0
(-27 1775);
DISPLAY 0.872340 (-27 1775);
PAINT GREEN (-27 1775);
DISPLAY INVISIBLE (-27 1775);
FORCEADD TAP..1
(-25 1375);
FORCEPROP 3 LASTPIN (-75 1375) SIG_NAME P5E_CPU0_P0_TX_C_DN<5>
J 0
(-65 1385);
DISPLAY 0.659574 (-65 1385);
PAINT MONO (-65 1385);
DISPLAY INVISIBLE (-65 1385);
FORCEPROP 1 LASTPIN (-75 1375) BN 5
J 0
(-87 1383);
DISPLAY 0.680851 (-87 1383);
PAINT GREEN (-87 1383);
FORCEPROP 2 LAST CDS_LIB standard
J 0
(-25 1375);
DISPLAY INVISIBLE (-25 1375);
FORCEPROP 1 LAST BODY_TYPE PLUMBING
J 0
(-25 1425);
DISPLAY 0.872340 (-25 1425);
PAINT GREEN (-25 1425);
DISPLAY INVISIBLE (-25 1425);
FORCEPROP 1 LAST HDL_TAP TRUE
J 0
(300 1250);
DISPLAY 0.872340 (300 1250);
DISPLAY INVISIBLE (300 1250);
FORCEPROP 1 LAST PATH I77
J 0
(-27 1375);
DISPLAY 0.872340 (-27 1375);
PAINT GREEN (-27 1375);
DISPLAY INVISIBLE (-27 1375);
FORCEADD TAP..1
(-25 1575);
FORCEPROP 3 LASTPIN (-75 1575) SIG_NAME P5E_CPU0_P0_TX_C_DN<6>
J 0
(-65 1585);
DISPLAY 0.659574 (-65 1585);
PAINT MONO (-65 1585);
DISPLAY INVISIBLE (-65 1585);
FORCEPROP 1 LASTPIN (-75 1575) BN 6
J 0
(-87 1583);
DISPLAY 0.680851 (-87 1583);
PAINT GREEN (-87 1583);
FORCEPROP 2 LAST CDS_LIB standard
J 0
(-25 1575);
DISPLAY INVISIBLE (-25 1575);
FORCEPROP 1 LAST BODY_TYPE PLUMBING
J 0
(-25 1625);
DISPLAY 0.872340 (-25 1625);
PAINT GREEN (-25 1625);
DISPLAY INVISIBLE (-25 1625);
FORCEPROP 1 LAST HDL_TAP TRUE
J 0
(300 1450);
DISPLAY 0.872340 (300 1450);
DISPLAY INVISIBLE (300 1450);
FORCEPROP 1 LAST PATH I78
J 0
(-27 1575);
DISPLAY 0.872340 (-27 1575);
PAINT GREEN (-27 1575);
DISPLAY INVISIBLE (-27 1575);
FORCEADD TAP..1
(-25 975);
FORCEPROP 3 LASTPIN (-75 975) SIG_NAME P5E_CPU0_P0_TX_C_DN<3>
J 0
(-65 985);
DISPLAY 0.659574 (-65 985);
PAINT MONO (-65 985);
DISPLAY INVISIBLE (-65 985);
FORCEPROP 1 LASTPIN (-75 975) BN 3
J 0
(-87 983);
DISPLAY 0.680851 (-87 983);
PAINT GREEN (-87 983);
FORCEPROP 2 LAST CDS_LIB standard
J 0
(-25 975);
DISPLAY INVISIBLE (-25 975);
FORCEPROP 1 LAST BODY_TYPE PLUMBING
J 0
(-25 1025);
DISPLAY 0.872340 (-25 1025);
PAINT GREEN (-25 1025);
DISPLAY INVISIBLE (-25 1025);
FORCEPROP 1 LAST HDL_TAP TRUE
J 0
(300 850);
DISPLAY 0.872340 (300 850);
DISPLAY INVISIBLE (300 850);
FORCEPROP 1 LAST PATH I79
J 0
(-27 975);
DISPLAY 0.872340 (-27 975);
PAINT GREEN (-27 975);
DISPLAY INVISIBLE (-27 975);
FORCEADD TAP..1
R 2
(-1300 575);
FORCEPROP 3 LASTPIN (-1250 575) SIG_NAME P5E_CPU0_P0_TX_DN<1>
J 0
(-1240 585);
DISPLAY 0.659574 (-1240 585);
PAINT MONO (-1240 585);
DISPLAY INVISIBLE (-1240 585);
FORCEPROP 1 LASTPIN (-1250 575) BN 1
J 2
(-1238 583);
DISPLAY 0.680851 (-1238 583);
PAINT GREEN (-1238 583);
FORCEPROP 2 LAST CDS_LIB standard
J 0
(-1300 575);
DISPLAY INVISIBLE (-1300 575);
FORCEPROP 1 LAST BODY_TYPE PLUMBING
J 2
(-1300 625);
DISPLAY 0.872340 (-1300 625);
PAINT GREEN (-1300 625);
DISPLAY INVISIBLE (-1300 625);
FORCEPROP 1 LAST HDL_TAP TRUE
J 2
(-1625 450);
DISPLAY 0.872340 (-1625 450);
DISPLAY INVISIBLE (-1625 450);
FORCEPROP 1 LAST PATH I8
J 2
(-1298 575);
DISPLAY 0.872340 (-1298 575);
PAINT GREEN (-1298 575);
DISPLAY INVISIBLE (-1298 575);
FORCEADD TAP..1
(-25 1175);
FORCEPROP 3 LASTPIN (-75 1175) SIG_NAME P5E_CPU0_P0_TX_C_DN<4>
J 0
(-65 1185);
DISPLAY 0.659574 (-65 1185);
PAINT MONO (-65 1185);
DISPLAY INVISIBLE (-65 1185);
FORCEPROP 1 LASTPIN (-75 1175) BN 4
J 0
(-87 1183);
DISPLAY 0.680851 (-87 1183);
PAINT GREEN (-87 1183);
FORCEPROP 2 LAST CDS_LIB standard
J 0
(-25 1175);
DISPLAY INVISIBLE (-25 1175);
FORCEPROP 1 LAST BODY_TYPE PLUMBING
J 0
(-25 1225);
DISPLAY 0.872340 (-25 1225);
PAINT GREEN (-25 1225);
DISPLAY INVISIBLE (-25 1225);
FORCEPROP 1 LAST HDL_TAP TRUE
J 0
(300 1050);
DISPLAY 0.872340 (300 1050);
DISPLAY INVISIBLE (300 1050);
FORCEPROP 1 LAST PATH I80
J 0
(-27 1175);
DISPLAY 0.872340 (-27 1175);
PAINT GREEN (-27 1175);
DISPLAY INVISIBLE (-27 1175);
FORCEADD TAP..1
(-25 775);
FORCEPROP 3 LASTPIN (-75 775) SIG_NAME P5E_CPU0_P0_TX_C_DN<2>
J 0
(-65 785);
DISPLAY 0.659574 (-65 785);
PAINT MONO (-65 785);
DISPLAY INVISIBLE (-65 785);
FORCEPROP 1 LASTPIN (-75 775) BN 2
J 0
(-87 783);
DISPLAY 0.680851 (-87 783);
PAINT GREEN (-87 783);
FORCEPROP 2 LAST CDS_LIB standard
J 0
(-25 775);
DISPLAY INVISIBLE (-25 775);
FORCEPROP 1 LAST BODY_TYPE PLUMBING
J 0
(-25 825);
DISPLAY 0.872340 (-25 825);
PAINT GREEN (-25 825);
DISPLAY INVISIBLE (-25 825);
FORCEPROP 1 LAST HDL_TAP TRUE
J 0
(300 650);
DISPLAY 0.872340 (300 650);
DISPLAY INVISIBLE (300 650);
FORCEPROP 1 LAST PATH I81
J 0
(-27 775);
DISPLAY 0.872340 (-27 775);
PAINT GREEN (-27 775);
DISPLAY INVISIBLE (-27 775);
FORCEADD TAP..1
(-25 575);
FORCEPROP 3 LASTPIN (-75 575) SIG_NAME P5E_CPU0_P0_TX_C_DN<1>
J 0
(-65 585);
DISPLAY 0.659574 (-65 585);
PAINT MONO (-65 585);
DISPLAY INVISIBLE (-65 585);
FORCEPROP 1 LASTPIN (-75 575) BN 1
J 0
(-87 583);
DISPLAY 0.680851 (-87 583);
PAINT GREEN (-87 583);
FORCEPROP 2 LAST CDS_LIB standard
J 0
(-25 575);
DISPLAY INVISIBLE (-25 575);
FORCEPROP 1 LAST BODY_TYPE PLUMBING
J 0
(-25 625);
DISPLAY 0.872340 (-25 625);
PAINT GREEN (-25 625);
DISPLAY INVISIBLE (-25 625);
FORCEPROP 1 LAST HDL_TAP TRUE
J 0
(300 450);
DISPLAY 0.872340 (300 450);
DISPLAY INVISIBLE (300 450);
FORCEPROP 1 LAST PATH I82
J 0
(-27 575);
DISPLAY 0.872340 (-27 575);
PAINT GREEN (-27 575);
DISPLAY INVISIBLE (-27 575);
FORCEADD TAP..1
(-25 375);
FORCEPROP 3 LASTPIN (-75 375) SIG_NAME P5E_CPU0_P0_TX_C_DN<0>
J 0
(-65 385);
DISPLAY 0.659574 (-65 385);
PAINT MONO (-65 385);
DISPLAY INVISIBLE (-65 385);
FORCEPROP 1 LASTPIN (-75 375) BN 0
J 0
(-87 383);
DISPLAY 0.680851 (-87 383);
PAINT GREEN (-87 383);
FORCEPROP 2 LAST CDS_LIB standard
J 0
(-25 375);
DISPLAY INVISIBLE (-25 375);
FORCEPROP 1 LAST BODY_TYPE PLUMBING
J 0
(-25 425);
DISPLAY 0.872340 (-25 425);
PAINT GREEN (-25 425);
DISPLAY INVISIBLE (-25 425);
FORCEPROP 1 LAST HDL_TAP TRUE
J 0
(300 250);
DISPLAY 0.872340 (300 250);
DISPLAY INVISIBLE (300 250);
FORCEPROP 1 LAST PATH I83
J 0
(-27 375);
DISPLAY 0.872340 (-27 375);
PAINT GREEN (-27 375);
DISPLAY INVISIBLE (-27 375);
FORCEADD TAP..1
(-25 3750);
FORCEPROP 3 LASTPIN (-75 3750) SIG_NAME P5E_CPU0_P0_TX_C_DN<15>
J 0
(-65 3760);
DISPLAY 0.659574 (-65 3760);
PAINT MONO (-65 3760);
DISPLAY INVISIBLE (-65 3760);
FORCEPROP 1 LASTPIN (-75 3750) BN 15
J 0
(-87 3758);
DISPLAY 0.680851 (-87 3758);
PAINT GREEN (-87 3758);
FORCEPROP 2 LAST CDS_LIB standard
J 0
(-25 3750);
DISPLAY INVISIBLE (-25 3750);
FORCEPROP 1 LAST BODY_TYPE PLUMBING
J 0
(-25 3800);
DISPLAY 0.872340 (-25 3800);
PAINT GREEN (-25 3800);
DISPLAY INVISIBLE (-25 3800);
FORCEPROP 1 LAST HDL_TAP TRUE
J 0
(300 3625);
DISPLAY 0.872340 (300 3625);
DISPLAY INVISIBLE (300 3625);
FORCEPROP 1 LAST PATH I84
J 0
(-27 3750);
DISPLAY 0.872340 (-27 3750);
PAINT GREEN (-27 3750);
DISPLAY INVISIBLE (-27 3750);
FORCEADD TAP..1
(175 325);
FORCEPROP 3 LASTPIN (125 325) SIG_NAME P5E_CPU0_P0_TX_C_DP<0>
J 0
(135 335);
DISPLAY 0.659574 (135 335);
PAINT MONO (135 335);
DISPLAY INVISIBLE (135 335);
FORCEPROP 1 LASTPIN (125 325) BN 0
J 0
(113 333);
DISPLAY 0.680851 (113 333);
PAINT GREEN (113 333);
FORCEPROP 2 LAST CDS_LIB standard
J 0
(175 325);
DISPLAY INVISIBLE (175 325);
FORCEPROP 1 LAST BODY_TYPE PLUMBING
J 0
(175 375);
DISPLAY 0.872340 (175 375);
PAINT GREEN (175 375);
DISPLAY INVISIBLE (175 375);
FORCEPROP 1 LAST HDL_TAP TRUE
J 0
(500 200);
DISPLAY 0.872340 (500 200);
DISPLAY INVISIBLE (500 200);
FORCEPROP 1 LAST PATH I85
J 0
(173 325);
DISPLAY 0.872340 (173 325);
PAINT GREEN (173 325);
DISPLAY INVISIBLE (173 325);
FORCEADD TAP..1
(175 525);
FORCEPROP 3 LASTPIN (125 525) SIG_NAME P5E_CPU0_P0_TX_C_DP<1>
J 0
(135 535);
DISPLAY 0.659574 (135 535);
PAINT MONO (135 535);
DISPLAY INVISIBLE (135 535);
FORCEPROP 1 LASTPIN (125 525) BN 1
J 0
(113 533);
DISPLAY 0.680851 (113 533);
PAINT GREEN (113 533);
FORCEPROP 2 LAST CDS_LIB standard
J 0
(175 525);
DISPLAY INVISIBLE (175 525);
FORCEPROP 1 LAST BODY_TYPE PLUMBING
J 0
(175 575);
DISPLAY 0.872340 (175 575);
PAINT GREEN (175 575);
DISPLAY INVISIBLE (175 575);
FORCEPROP 1 LAST HDL_TAP TRUE
J 0
(500 400);
DISPLAY 0.872340 (500 400);
DISPLAY INVISIBLE (500 400);
FORCEPROP 1 LAST PATH I86
J 0
(173 525);
DISPLAY 0.872340 (173 525);
PAINT GREEN (173 525);
DISPLAY INVISIBLE (173 525);
FORCEADD TAP..1
(175 725);
FORCEPROP 3 LASTPIN (125 725) SIG_NAME P5E_CPU0_P0_TX_C_DP<2>
J 0
(135 735);
DISPLAY 0.659574 (135 735);
PAINT MONO (135 735);
DISPLAY INVISIBLE (135 735);
FORCEPROP 1 LASTPIN (125 725) BN 2
J 0
(113 733);
DISPLAY 0.680851 (113 733);
PAINT GREEN (113 733);
FORCEPROP 2 LAST CDS_LIB standard
J 0
(175 725);
DISPLAY INVISIBLE (175 725);
FORCEPROP 1 LAST BODY_TYPE PLUMBING
J 0
(175 775);
DISPLAY 0.872340 (175 775);
PAINT GREEN (175 775);
DISPLAY INVISIBLE (175 775);
FORCEPROP 1 LAST HDL_TAP TRUE
J 0
(500 600);
DISPLAY 0.872340 (500 600);
DISPLAY INVISIBLE (500 600);
FORCEPROP 1 LAST PATH I87
J 0
(173 725);
DISPLAY 0.872340 (173 725);
PAINT GREEN (173 725);
DISPLAY INVISIBLE (173 725);
FORCEADD TAP..1
(175 925);
FORCEPROP 3 LASTPIN (125 925) SIG_NAME P5E_CPU0_P0_TX_C_DP<3>
J 0
(135 935);
DISPLAY 0.659574 (135 935);
PAINT MONO (135 935);
DISPLAY INVISIBLE (135 935);
FORCEPROP 1 LASTPIN (125 925) BN 3
J 0
(113 933);
DISPLAY 0.680851 (113 933);
PAINT GREEN (113 933);
FORCEPROP 2 LAST CDS_LIB standard
J 0
(175 925);
DISPLAY INVISIBLE (175 925);
FORCEPROP 1 LAST BODY_TYPE PLUMBING
J 0
(175 975);
DISPLAY 0.872340 (175 975);
PAINT GREEN (175 975);
DISPLAY INVISIBLE (175 975);
FORCEPROP 1 LAST HDL_TAP TRUE
J 0
(500 800);
DISPLAY 0.872340 (500 800);
DISPLAY INVISIBLE (500 800);
FORCEPROP 1 LAST PATH I88
J 0
(173 925);
DISPLAY 0.872340 (173 925);
PAINT GREEN (173 925);
DISPLAY INVISIBLE (173 925);
FORCEADD TAP..1
(175 1125);
FORCEPROP 3 LASTPIN (125 1125) SIG_NAME P5E_CPU0_P0_TX_C_DP<4>
J 0
(135 1135);
DISPLAY 0.659574 (135 1135);
PAINT MONO (135 1135);
DISPLAY INVISIBLE (135 1135);
FORCEPROP 1 LASTPIN (125 1125) BN 4
J 0
(113 1133);
DISPLAY 0.680851 (113 1133);
PAINT GREEN (113 1133);
FORCEPROP 2 LAST CDS_LIB standard
J 0
(175 1125);
DISPLAY INVISIBLE (175 1125);
FORCEPROP 1 LAST BODY_TYPE PLUMBING
J 0
(175 1175);
DISPLAY 0.872340 (175 1175);
PAINT GREEN (175 1175);
DISPLAY INVISIBLE (175 1175);
FORCEPROP 1 LAST HDL_TAP TRUE
J 0
(500 1000);
DISPLAY 0.872340 (500 1000);
DISPLAY INVISIBLE (500 1000);
FORCEPROP 1 LAST PATH I89
J 0
(173 1125);
DISPLAY 0.872340 (173 1125);
PAINT GREEN (173 1125);
DISPLAY INVISIBLE (173 1125);
FORCEADD TAP..1
R 2
(-1550 725);
FORCEPROP 3 LASTPIN (-1500 725) SIG_NAME P5E_CPU0_P0_TX_DP<2>
J 0
(-1490 735);
DISPLAY 0.659574 (-1490 735);
PAINT MONO (-1490 735);
DISPLAY INVISIBLE (-1490 735);
FORCEPROP 1 LASTPIN (-1500 725) BN 2
J 2
(-1488 733);
DISPLAY 0.680851 (-1488 733);
PAINT GREEN (-1488 733);
FORCEPROP 2 LAST CDS_LIB standard
J 0
(-1550 725);
DISPLAY INVISIBLE (-1550 725);
FORCEPROP 1 LAST BODY_TYPE PLUMBING
J 2
(-1550 775);
DISPLAY 0.872340 (-1550 775);
PAINT GREEN (-1550 775);
DISPLAY INVISIBLE (-1550 775);
FORCEPROP 1 LAST HDL_TAP TRUE
J 2
(-1875 600);
DISPLAY 0.872340 (-1875 600);
DISPLAY INVISIBLE (-1875 600);
FORCEPROP 1 LAST PATH I9
J 2
(-1548 725);
DISPLAY 0.872340 (-1548 725);
PAINT GREEN (-1548 725);
DISPLAY INVISIBLE (-1548 725);
FORCEADD TAP..1
(175 1325);
FORCEPROP 3 LASTPIN (125 1325) SIG_NAME P5E_CPU0_P0_TX_C_DP<5>
J 0
(135 1335);
DISPLAY 0.659574 (135 1335);
PAINT MONO (135 1335);
DISPLAY INVISIBLE (135 1335);
FORCEPROP 1 LASTPIN (125 1325) BN 5
J 0
(113 1333);
DISPLAY 0.680851 (113 1333);
PAINT GREEN (113 1333);
FORCEPROP 2 LAST CDS_LIB standard
J 0
(175 1325);
DISPLAY INVISIBLE (175 1325);
FORCEPROP 1 LAST BODY_TYPE PLUMBING
J 0
(175 1375);
DISPLAY 0.872340 (175 1375);
PAINT GREEN (175 1375);
DISPLAY INVISIBLE (175 1375);
FORCEPROP 1 LAST HDL_TAP TRUE
J 0
(500 1200);
DISPLAY 0.872340 (500 1200);
DISPLAY INVISIBLE (500 1200);
FORCEPROP 1 LAST PATH I90
J 0
(173 1325);
DISPLAY 0.872340 (173 1325);
PAINT GREEN (173 1325);
DISPLAY INVISIBLE (173 1325);
FORCEADD TAP..1
(175 1525);
FORCEPROP 3 LASTPIN (125 1525) SIG_NAME P5E_CPU0_P0_TX_C_DP<6>
J 0
(135 1535);
DISPLAY 0.659574 (135 1535);
PAINT MONO (135 1535);
DISPLAY INVISIBLE (135 1535);
FORCEPROP 1 LASTPIN (125 1525) BN 6
J 0
(113 1533);
DISPLAY 0.680851 (113 1533);
PAINT GREEN (113 1533);
FORCEPROP 2 LAST CDS_LIB standard
J 0
(175 1525);
DISPLAY INVISIBLE (175 1525);
FORCEPROP 1 LAST BODY_TYPE PLUMBING
J 0
(175 1575);
DISPLAY 0.872340 (175 1575);
PAINT GREEN (175 1575);
DISPLAY INVISIBLE (175 1575);
FORCEPROP 1 LAST HDL_TAP TRUE
J 0
(500 1400);
DISPLAY 0.872340 (500 1400);
DISPLAY INVISIBLE (500 1400);
FORCEPROP 1 LAST PATH I91
J 0
(173 1525);
DISPLAY 0.872340 (173 1525);
PAINT GREEN (173 1525);
DISPLAY INVISIBLE (173 1525);
FORCEADD TAP..1
(175 1725);
FORCEPROP 3 LASTPIN (125 1725) SIG_NAME P5E_CPU0_P0_TX_C_DP<7>
J 0
(135 1735);
DISPLAY 0.659574 (135 1735);
PAINT MONO (135 1735);
DISPLAY INVISIBLE (135 1735);
FORCEPROP 1 LASTPIN (125 1725) BN 7
J 0
(113 1733);
DISPLAY 0.680851 (113 1733);
PAINT GREEN (113 1733);
FORCEPROP 2 LAST CDS_LIB standard
J 0
(175 1725);
DISPLAY INVISIBLE (175 1725);
FORCEPROP 1 LAST BODY_TYPE PLUMBING
J 0
(175 1775);
DISPLAY 0.872340 (175 1775);
PAINT GREEN (175 1775);
DISPLAY INVISIBLE (175 1775);
FORCEPROP 1 LAST HDL_TAP TRUE
J 0
(500 1600);
DISPLAY 0.872340 (500 1600);
DISPLAY INVISIBLE (500 1600);
FORCEPROP 1 LAST PATH I92
J 0
(173 1725);
DISPLAY 0.872340 (173 1725);
PAINT GREEN (173 1725);
DISPLAY INVISIBLE (173 1725);
FORCEADD OFFPAGE..2
(1175 1750);
FORCEPROP 2 LAST $XR0 273 
J 0
(1364 1750);
DISPLAY 0.638298 (1364 1750);
PAINT MONO (1364 1750);
FORCEPROP 2 LAST CDS_LIB standard
J 0
(1175 1750);
DISPLAY INVISIBLE (1175 1750);
FORCEPROP 1 LAST OFFPAGE TRUE
J 0
(1500 1625);
DISPLAY 0.872340 (1500 1625);
DISPLAY INVISIBLE (1500 1625);
FORCEPROP 1 LAST COMMENT_BODY TRUE
J 0
(1130 1655);
DISPLAY 0.872340 (1130 1655);
PAINT GREEN (1130 1655);
DISPLAY INVISIBLE (1130 1655);
FORCEPROP 2 LAST PATH I93
J 0
(1375 1800);
DISPLAY 1.021277 (1375 1800);
DISPLAY INVISIBLE (1375 1800);
FORCEADD OFFPAGE..2
(1175 1800);
FORCEPROP 2 LAST $XR0 273 
J 0
(1364 1800);
DISPLAY 0.638298 (1364 1800);
PAINT MONO (1364 1800);
FORCEPROP 2 LAST CDS_LIB standard
J 0
(1175 1800);
DISPLAY INVISIBLE (1175 1800);
FORCEPROP 1 LAST OFFPAGE TRUE
J 0
(1500 1675);
DISPLAY 0.872340 (1500 1675);
DISPLAY INVISIBLE (1500 1675);
FORCEPROP 1 LAST COMMENT_BODY TRUE
J 0
(1130 1705);
DISPLAY 0.872340 (1130 1705);
PAINT GREEN (1130 1705);
DISPLAY INVISIBLE (1130 1705);
FORCEPROP 2 LAST PATH I94
J 0
(1375 1850);
DISPLAY 1.021277 (1375 1850);
DISPLAY INVISIBLE (1375 1850);
FORCEADD OFFPAGE..1
(2050 1750);
FORCEPROP 2 LAST $XR0 24 
J 0
(1829 1750);
DISPLAY 0.638298 (1829 1750);
PAINT MONO (1829 1750);
FORCEPROP 2 LAST CDS_LIB standard
J 0
(2050 1750);
DISPLAY INVISIBLE (2050 1750);
FORCEPROP 1 LAST OFFPAGE TRUE
J 0
(2375 1625);
DISPLAY 0.872340 (2375 1625);
DISPLAY INVISIBLE (2375 1625);
FORCEPROP 1 LAST COMMENT_BODY TRUE
J 0
(2175 1650);
DISPLAY 0.872340 (2175 1650);
PAINT GREEN (2175 1650);
DISPLAY INVISIBLE (2175 1650);
FORCEPROP 2 LAST PATH I95
J 0
(1800 1800);
DISPLAY 1.021277 (1800 1800);
DISPLAY INVISIBLE (1800 1800);
FORCEADD OFFPAGE..1
(2050 1800);
FORCEPROP 2 LAST $XR0 24 
J 0
(1829 1800);
DISPLAY 0.638298 (1829 1800);
PAINT MONO (1829 1800);
FORCEPROP 2 LAST CDS_LIB standard
J 0
(2050 1800);
DISPLAY INVISIBLE (2050 1800);
FORCEPROP 1 LAST OFFPAGE TRUE
J 0
(2375 1675);
DISPLAY 0.872340 (2375 1675);
DISPLAY INVISIBLE (2375 1675);
FORCEPROP 1 LAST COMMENT_BODY TRUE
J 0
(2175 1700);
DISPLAY 0.872340 (2175 1700);
PAINT GREEN (2175 1700);
DISPLAY INVISIBLE (2175 1700);
FORCEPROP 2 LAST PATH I96
J 0
(1800 1850);
DISPLAY 1.021277 (1800 1850);
DISPLAY INVISIBLE (1800 1850);
FORCEADD TAP..1
(175 2300);
FORCEPROP 3 LASTPIN (125 2300) SIG_NAME P5E_CPU0_P0_TX_C_DP<8>
J 0
(135 2310);
DISPLAY 0.659574 (135 2310);
PAINT MONO (135 2310);
DISPLAY INVISIBLE (135 2310);
FORCEPROP 1 LASTPIN (125 2300) BN 8
J 0
(113 2308);
DISPLAY 0.680851 (113 2308);
PAINT GREEN (113 2308);
FORCEPROP 2 LAST CDS_LIB standard
J 0
(175 2300);
DISPLAY INVISIBLE (175 2300);
FORCEPROP 1 LAST BODY_TYPE PLUMBING
J 0
(175 2350);
DISPLAY 0.872340 (175 2350);
PAINT GREEN (175 2350);
DISPLAY INVISIBLE (175 2350);
FORCEPROP 1 LAST HDL_TAP TRUE
J 0
(500 2175);
DISPLAY 0.872340 (500 2175);
DISPLAY INVISIBLE (500 2175);
FORCEPROP 1 LAST PATH I97
J 0
(173 2300);
DISPLAY 0.872340 (173 2300);
PAINT GREEN (173 2300);
DISPLAY INVISIBLE (173 2300);
FORCEADD TAP..1
(175 2500);
FORCEPROP 3 LASTPIN (125 2500) SIG_NAME P5E_CPU0_P0_TX_C_DP<9>
J 0
(135 2510);
DISPLAY 0.659574 (135 2510);
PAINT MONO (135 2510);
DISPLAY INVISIBLE (135 2510);
FORCEPROP 1 LASTPIN (125 2500) BN 9
J 0
(113 2508);
DISPLAY 0.680851 (113 2508);
PAINT GREEN (113 2508);
FORCEPROP 2 LAST CDS_LIB standard
J 0
(175 2500);
DISPLAY INVISIBLE (175 2500);
FORCEPROP 1 LAST BODY_TYPE PLUMBING
J 0
(175 2550);
DISPLAY 0.872340 (175 2550);
PAINT GREEN (175 2550);
DISPLAY INVISIBLE (175 2550);
FORCEPROP 1 LAST HDL_TAP TRUE
J 0
(500 2375);
DISPLAY 0.872340 (500 2375);
DISPLAY INVISIBLE (500 2375);
FORCEPROP 1 LAST PATH I98
J 0
(173 2500);
DISPLAY 0.872340 (173 2500);
PAINT GREEN (173 2500);
DISPLAY INVISIBLE (173 2500);
FORCEADD TAP..1
(175 2900);
FORCEPROP 3 LASTPIN (125 2900) SIG_NAME P5E_CPU0_P0_TX_C_DP<11>
J 0
(135 2910);
DISPLAY 0.659574 (135 2910);
PAINT MONO (135 2910);
DISPLAY INVISIBLE (135 2910);
FORCEPROP 1 LASTPIN (125 2900) BN 11
J 0
(113 2908);
DISPLAY 0.680851 (113 2908);
PAINT GREEN (113 2908);
FORCEPROP 2 LAST CDS_LIB standard
J 0
(175 2900);
DISPLAY INVISIBLE (175 2900);
FORCEPROP 1 LAST BODY_TYPE PLUMBING
J 0
(175 2950);
DISPLAY 0.872340 (175 2950);
PAINT GREEN (175 2950);
DISPLAY INVISIBLE (175 2950);
FORCEPROP 1 LAST HDL_TAP TRUE
J 0
(500 2775);
DISPLAY 0.872340 (500 2775);
DISPLAY INVISIBLE (500 2775);
FORCEPROP 1 LAST PATH I99
J 0
(173 2900);
DISPLAY 0.872340 (173 2900);
PAINT GREEN (173 2900);
DISPLAY INVISIBLE (173 2900);
FORCEADD QUANTA_TITLE_BLOCK_C..1
(6300 -1650);
FORCEPROP 0 LAST CDS_CON_LAST_MODIFIED Thu Sep 14 16:12:28 2023
J 0
(4415 -1635);
DISPLAY INVISIBLE (4415 -1635);
FORCEPROP 2 LAST CUSTOM_TXT_CDS <XR_PAGE_TITLE>
J 0
(-1590 3600);
DISPLAY 0.638298 (-1590 3600);
PAINT PINK (-1590 3600);
DISPLAY INVISIBLE (-1590 3600);
FORCEPROP 2 LAST CUSTOM_TXT_CDS <CON_PAGE_NUM> OF <CON_TOTAL_PAGES>
J 0
(5854 -1632);
DISPLAY 0.978723 (5854 -1632);
FORCEPROP 2 LAST CUSTOM_TXT_CDS <Q_REV>
J 0
(6116 -1547);
DISPLAY 1.212766 (6116 -1547);
FORCEPROP 2 LAST CUSTOM_TXT_CDS <Q_PROJ>
J 0
(3918 -1548);
DISPLAY 1.212766 (3918 -1548);
FORCEPROP 2 LAST CUSTOM_TXT_CDS <Q_NUMBER>
J 0
(4897 -1547);
DISPLAY 1.212766 (4897 -1547);
FORCEPROP 2 LAST CUSTOM_TXT_CDS <CON_LAST_MODIFIED>
J 0
(4415 -1635);
DISPLAY 0.978723 (4415 -1635);
FORCEPROP 1 LAST CUSTOM_TXT_CDS <NAME_2>
J 0
(3125 -1600);
FORCEPROP 1 LAST CUSTOM_TXT_CDS <NAME_1>
J 0
(3125 -1475);
FORCEPROP 1 LAST Q_TITLE PCIE AC-COUPLE CAPS 1/5
J 0
(-3066 -1624);
DISPLAY 2.446809 (-3066 -1624);
PAINT GREEN (-3066 -1624);
FORCEPROP 2 LAST CDS_LIB pure_quanta
J 0
(6300 -1650);
DISPLAY INVISIBLE (6300 -1650);
FORCEPROP 1 LAST CDS_LMAN_SYM_OUTLINE -9475,6775,100,-125
J 0
(6300 -1650);
DISPLAY 0.468085 (6300 -1650);
PAINT GREEN (6300 -1650);
DISPLAY INVISIBLE (6300 -1650);
FORCEPROP 2 LAST PAGE_BORDER TRUE
J 0
(-1590 3600);
DISPLAY 0.638298 (-1590 3600);
PAINT PINK (-1590 3600);
DISPLAY INVISIBLE (-1590 3600);
FORCEPROP 2 LAST CDS_XR_PAGE_TITLE CR-63 : @T6G_MB_LIB.T6G(SCH_1):PAGE63
J 0
(-1590 3600);
DISPLAY 0.638298 (-1590 3600);
PAINT PINK (-1590 3600);
DISPLAY INVISIBLE (-1590 3600);
FORCEPROP 1 LAST COMMENT_BODY TRUE
J 0
(6312 -1663);
DISPLAY 0.978723 (6312 -1663);
PAINT GREEN (6312 -1663);
DISPLAY INVISIBLE (6312 -1663);
FORCEPROP 1 LAST Q_DEPT CCBU
J 1
(2537 -1601);
DISPLAY 1.957447 (2537 -1601);
PAINT GREEN (2537 -1601);
DISPLAY INVISIBLE (2537 -1601);
WIRE 17 -1 (4775 950)(4775 1150);
WIRE 17 -1 (4775 950)(4775 750);
WIRE 17 -1 (4775 1350)(4775 1150);
WIRE 17 -1 (4775 1550)(4775 1350);
WIRE 17 -1 (4775 750)(4775 550);
WIRE 17 -1 (4775 550)(4775 350);
WIRE 17 -1 (4775 1750)(4775 1550);
WIRE 17 -1 (4775 1750)(5675 1750);
FORCEPROP 2 LAST SIG_NAME P5E_CPU0_P1_TX_C_DP<7:0>
J 0
(4815 1760);
DISPLAY 0.680851 (4815 1760);
PAINT WHITE (4815 1760);
WIRE 17 -1 (4575 3775)(5675 3775);
FORCEPROP 2 LAST SIG_NAME P5E_CPU0_P1_TX_C_DN<15:8>
J 0
(4815 3785);
DISPLAY 0.680851 (4815 3785);
PAINT WHITE (4815 3785);
WIRE 17 -1 (4575 3575)(4575 3375);
WIRE 17 -1 (4575 3775)(4575 3575);
WIRE 17 -1 (4575 3375)(4575 3175);
WIRE 17 -1 (4575 2975)(4575 3175);
WIRE 17 -1 (4575 2975)(4575 2775);
WIRE 17 -1 (4575 2775)(4575 2575);
WIRE 17 -1 (4575 2575)(4575 2375);
WIRE 17 -1 (2950 350)(2950 550);
WIRE 17 -1 (2950 550)(2950 750);
WIRE 17 -1 (2950 750)(2950 950);
WIRE 17 -1 (2950 950)(2950 1150);
WIRE 17 -1 (2950 1150)(2950 1350);
WIRE 17 -1 (2950 1350)(2950 1550);
WIRE 17 -1 (2950 1550)(2950 1750);
WIRE 17 -1 (2100 1750)(2950 1750);
FORCEPROP 2 LAST SIG_NAME P5E_CPU0_P1_TX_DP<7:0>
J 0
(2140 1760);
DISPLAY 0.680851 (2140 1760);
PAINT WHITE (2140 1760);
WIRE 17 -1 (3200 1800)(3200 1600);
WIRE 17 -1 (2100 1800)(3200 1800);
FORCEPROP 2 LAST SIG_NAME P5E_CPU0_P1_TX_DN<7:0>
J 0
(2140 1810);
DISPLAY 0.680851 (2140 1810);
PAINT WHITE (2140 1810);
WIRE 17 -1 (3200 3575)(3200 3375);
WIRE 17 -1 (3200 3775)(3200 3575);
WIRE 17 -1 (3200 3375)(3200 3175);
WIRE 17 -1 (3200 2975)(3200 3175);
WIRE 17 -1 (2100 3775)(3200 3775);
FORCEPROP 2 LAST SIG_NAME P5E_CPU0_P1_TX_DN<15:8>
J 0
(2140 3785);
DISPLAY 0.680851 (2140 3785);
PAINT WHITE (2140 3785);
WIRE 17 -1 (3200 2975)(3200 2775);
WIRE 17 -1 (3200 2775)(3200 2575);
WIRE 17 -1 (3200 2575)(3200 2375);
WIRE 17 -1 (3200 1000)(3200 800);
WIRE 17 -1 (3200 1000)(3200 1200);
WIRE 17 -1 (3200 800)(3200 600);
WIRE 17 -1 (3200 600)(3200 400);
WIRE 17 -1 (3200 1400)(3200 1200);
WIRE 17 -1 (3200 1600)(3200 1400);
WIRE 17 -1 (25 2975)(25 2775);
WIRE 17 -1 (25 2975)(25 3175);
WIRE 17 -1 (25 2775)(25 2575);
WIRE 17 -1 (25 2575)(25 2375);
WIRE 17 -1 (25 3375)(25 3175);
WIRE 17 -1 (25 3575)(25 3375);
WIRE 17 -1 (25 3775)(25 3575);
WIRE 17 -1 (25 3775)(1125 3775);
FORCEPROP 2 LAST SIG_NAME P5E_CPU0_P0_TX_C_DN<15:8>
J 0
(290 3785);
DISPLAY 0.680851 (290 3785);
PAINT WHITE (290 3785);
WIRE 17 -1 (225 950)(225 1150);
WIRE 17 -1 (225 950)(225 750);
WIRE 17 -1 (225 1350)(225 1150);
WIRE 17 -1 (225 1550)(225 1350);
WIRE 17 -1 (225 750)(225 550);
WIRE 17 -1 (225 550)(225 350);
WIRE 17 -1 (225 1750)(225 1550);
WIRE 17 -1 (225 1750)(1125 1750);
FORCEPROP 2 LAST SIG_NAME P5E_CPU0_P0_TX_C_DP<7:0>
J 0
(290 1760);
DISPLAY 0.680851 (290 1760);
PAINT WHITE (290 1760);
WIRE 17 -1 (25 1000)(25 1200);
WIRE 17 -1 (25 1000)(25 800);
WIRE 17 -1 (25 1400)(25 1200);
WIRE 17 -1 (25 1600)(25 1400);
WIRE 17 -1 (25 800)(25 600);
WIRE 17 -1 (25 600)(25 400);
WIRE 17 -1 (25 1800)(25 1600);
WIRE 17 -1 (25 1800)(1125 1800);
FORCEPROP 2 LAST SIG_NAME P5E_CPU0_P0_TX_C_DN<7:0>
J 0
(290 1810);
DISPLAY 0.680851 (290 1810);
PAINT WHITE (290 1810);
WIRE 17 -1 (225 3325)(225 3125);
WIRE 17 -1 (225 3525)(225 3325);
WIRE 17 -1 (225 2925)(225 3125);
WIRE 17 -1 (225 2925)(225 2725);
WIRE 17 -1 (225 3725)(225 3525);
WIRE 17 -1 (225 3725)(1125 3725);
FORCEPROP 2 LAST SIG_NAME P5E_CPU0_P0_TX_C_DP<15:8>
J 0
(290 3735);
DISPLAY 0.680851 (290 3735);
PAINT WHITE (290 3735);
WIRE 17 -1 (-1600 750)(-1600 950);
WIRE 17 -1 (-1600 550)(-1600 750);
WIRE 17 -1 (-1600 950)(-1600 1150);
WIRE 17 -1 (-1600 1150)(-1600 1350);
WIRE 17 -1 (-1600 350)(-1600 550);
WIRE 17 -1 (-1600 1350)(-1600 1550);
WIRE 17 -1 (-1600 1550)(-1600 1750);
WIRE 17 -1 (-2450 1750)(-1600 1750);
FORCEPROP 2 LAST SIG_NAME P5E_CPU0_P0_TX_DP<7:0>
J 0
(-2435 1760);
DISPLAY 0.680851 (-2435 1760);
PAINT WHITE (-2435 1760);
WIRE 17 -1 (225 2725)(225 2525);
WIRE 17 -1 (225 2525)(225 2325);
WIRE 17 -1 (-1600 2525)(-1600 2725);
WIRE 17 -1 (-1600 2325)(-1600 2525);
WIRE 17 -1 (-1600 2725)(-1600 2925);
WIRE 17 -1 (-1600 2925)(-1600 3125);
WIRE 17 -1 (-1600 3125)(-1600 3325);
WIRE 17 -1 (-1600 3325)(-1600 3525);
WIRE 17 -1 (-1600 3525)(-1600 3725);
WIRE 17 -1 (-2450 3725)(-1600 3725);
FORCEPROP 2 LAST SIG_NAME P5E_CPU0_P0_TX_DP<15:8>
J 0
(-2435 3735);
DISPLAY 0.680851 (-2435 3735);
PAINT WHITE (-2435 3735);
WIRE 17 -1 (-1350 2775)(-1350 2575);
WIRE 17 -1 (-1350 2975)(-1350 2775);
WIRE 17 -1 (-1350 2575)(-1350 2375);
WIRE 17 -1 (-1350 2975)(-1350 3175);
WIRE 17 -1 (-1350 3375)(-1350 3175);
WIRE 17 -1 (-1350 3575)(-1350 3375);
WIRE 17 -1 (-1350 3775)(-1350 3575);
WIRE 17 -1 (-2450 3775)(-1350 3775);
FORCEPROP 2 LAST SIG_NAME P5E_CPU0_P0_TX_DN<15:8>
J 0
(-2435 3785);
DISPLAY 0.680851 (-2435 3785);
PAINT WHITE (-2435 3785);
WIRE 17 -1 (-1350 1800)(-1350 1600);
WIRE 17 -1 (-2450 1800)(-1350 1800);
FORCEPROP 2 LAST SIG_NAME P5E_CPU0_P0_TX_DN<7:0>
J 0
(-2435 1810);
DISPLAY 0.680851 (-2435 1810);
PAINT WHITE (-2435 1810);
WIRE 17 -1 (-1350 1400)(-1350 1200);
WIRE 17 -1 (-1350 1600)(-1350 1400);
WIRE 17 -1 (-1350 1000)(-1350 1200);
WIRE 17 -1 (-1350 1000)(-1350 800);
WIRE 17 -1 (-1350 600)(-1350 400);
WIRE 17 -1 (-1350 800)(-1350 600);
WIRE 17 -1 (2950 2325)(2950 2525);
WIRE 17 -1 (2950 2525)(2950 2725);
WIRE 17 -1 (2950 2725)(2950 2925);
WIRE 17 -1 (2950 2925)(2950 3125);
WIRE 17 -1 (2950 3125)(2950 3325);
WIRE 17 -1 (2950 3325)(2950 3525);
WIRE 17 -1 (2950 3525)(2950 3725);
WIRE 17 -1 (2100 3725)(2950 3725);
FORCEPROP 2 LAST SIG_NAME P5E_CPU0_P1_TX_DP<15:8>
J 0
(2140 3735);
DISPLAY 0.680851 (2140 3735);
PAINT WHITE (2140 3735);
WIRE 17 -1 (4775 2925)(4775 2725);
WIRE 17 -1 (4775 2925)(4775 3125);
WIRE 17 -1 (4775 2725)(4775 2525);
WIRE 17 -1 (4775 2525)(4775 2325);
WIRE 17 -1 (4775 3325)(4775 3125);
WIRE 17 -1 (4775 3525)(4775 3325);
WIRE 17 -1 (4775 3725)(4775 3525);
WIRE 17 -1 (4775 3725)(5675 3725);
FORCEPROP 2 LAST SIG_NAME P5E_CPU0_P1_TX_C_DP<15:8>
J 0
(4815 3735);
DISPLAY 0.680851 (4815 3735);
PAINT WHITE (4815 3735);
WIRE 17 -1 (4575 1000)(4575 800);
WIRE 17 -1 (4575 1000)(4575 1200);
WIRE 17 -1 (4575 800)(4575 600);
WIRE 17 -1 (4575 600)(4575 400);
WIRE 17 -1 (4575 1400)(4575 1200);
WIRE 17 -1 (4575 1600)(4575 1400);
WIRE 17 -1 (4575 1800)(4575 1600);
WIRE 17 -1 (4575 1800)(5675 1800);
FORCEPROP 2 LAST SIG_NAME P5E_CPU0_P1_TX_C_DN<7:0>
J 0
(4815 1810);
DISPLAY 0.680851 (4815 1810);
PAINT WHITE (4815 1810);
WIRE 16 -1 (-500 3750)(-75 3750);
WIRE 16 -1 (-650 3700)(-1500 3700);
WIRE 16 -1 (4050 375)(4475 375);
WIRE 16 -1 (4050 975)(4475 975);
WIRE 16 -1 (4050 1575)(4475 1575);
WIRE 16 -1 (4050 1375)(4475 1375);
WIRE 16 -1 (4050 1175)(4475 1175);
WIRE 16 -1 (4050 1775)(4475 1775);
WIRE 16 -1 (4050 575)(4475 575);
WIRE 16 -1 (4050 775)(4475 775);
WIRE 16 -1 (4050 3500)(4675 3500);
WIRE 16 -1 (4050 3700)(4675 3700);
WIRE 16 -1 (4050 3300)(4675 3300);
WIRE 16 -1 (4050 3100)(4675 3100);
WIRE 16 -1 (4050 2500)(4675 2500);
WIRE 16 -1 (4050 2300)(4675 2300);
WIRE 16 -1 (4050 2900)(4675 2900);
WIRE 16 -1 (4050 2700)(4675 2700);
WIRE 16 -1 (3900 3750)(3300 3750);
WIRE 16 -1 (3900 3550)(3300 3550);
WIRE 16 -1 (3900 3500)(3050 3500);
WIRE 16 -1 (3900 2350)(3300 2350);
WIRE 16 -1 (3900 2500)(3050 2500);
WIRE 16 -1 (3900 2700)(3050 2700);
WIRE 16 -1 (3900 2900)(3050 2900);
WIRE 16 -1 (3900 3100)(3050 3100);
WIRE 16 -1 (3900 3300)(3050 3300);
WIRE 16 -1 (3900 3700)(3050 3700);
WIRE 16 -1 (3900 2300)(3050 2300);
WIRE 16 -1 (3900 1375)(3300 1375);
WIRE 16 -1 (3900 1175)(3300 1175);
WIRE 16 -1 (3900 2950)(3300 2950);
WIRE 16 -1 (3900 2550)(3300 2550);
WIRE 16 -1 (3900 1725)(3050 1725);
WIRE 16 -1 (-500 2300)(125 2300);
WIRE 16 -1 (-650 2350)(-1250 2350);
WIRE 16 -1 (-650 2900)(-1500 2900);
WIRE 16 -1 (-500 2900)(125 2900);
WIRE 16 -1 (-500 2700)(125 2700);
WIRE 16 -1 (-650 2700)(-1500 2700);
WIRE 16 -1 (-650 2300)(-1500 2300);
WIRE 16 -1 (-650 2750)(-1250 2750);
WIRE 16 -1 (-650 3550)(-1250 3550);
WIRE 16 -1 (-650 3750)(-1250 3750);
WIRE 16 -1 (-650 1775)(-1250 1775);
WIRE 16 -1 (-650 575)(-1250 575);
WIRE 16 -1 (-650 1375)(-1250 1375);
WIRE 16 -1 (-650 975)(-1250 975);
WIRE 16 -1 (-650 775)(-1250 775);
WIRE 16 -1 (-650 375)(-1250 375);
WIRE 16 -1 (-650 1175)(-1250 1175);
WIRE 16 -1 (-650 1575)(-1250 1575);
WIRE 16 -1 (-650 3350)(-1250 3350);
WIRE 16 -1 (-650 3150)(-1250 3150);
WIRE 16 -1 (-650 2950)(-1250 2950);
WIRE 16 -1 (-650 2550)(-1250 2550);
WIRE 16 -1 (-650 3100)(-1500 3100);
WIRE 16 -1 (-650 3300)(-1500 3300);
WIRE 16 -1 (-650 3500)(-1500 3500);
WIRE 16 -1 (-650 2500)(-1500 2500);
WIRE 16 -1 (-500 1525)(125 1525);
WIRE 16 -1 (-500 1575)(-75 1575);
WIRE 16 -1 (-500 1725)(125 1725);
WIRE 16 -1 (-500 1775)(-75 1775);
WIRE 16 -1 (-500 2350)(-75 2350);
WIRE 16 -1 (-500 2500)(125 2500);
WIRE 16 -1 (-650 1725)(-1500 1725);
WIRE 16 -1 (-500 325)(125 325);
WIRE 16 -1 (-500 725)(125 725);
WIRE 16 -1 (-500 775)(-75 775);
WIRE 16 -1 (-650 1125)(-1500 1125);
WIRE 16 -1 (-650 1325)(-1500 1325);
WIRE 16 -1 (-650 925)(-1500 925);
WIRE 16 -1 (-500 2550)(-75 2550);
WIRE 16 -1 (-650 325)(-1500 325);
WIRE 16 -1 (-650 525)(-1500 525);
WIRE 16 -1 (-650 1525)(-1500 1525);
WIRE 16 -1 (-650 725)(-1500 725);
WIRE 16 -1 (-500 3350)(-75 3350);
WIRE 16 -1 (-500 3500)(125 3500);
WIRE 16 -1 (-500 3700)(125 3700);
WIRE 16 -1 (-500 2950)(-75 2950);
WIRE 16 -1 (-500 3300)(125 3300);
WIRE 16 -1 (-500 3150)(-75 3150);
WIRE 16 -1 (-500 3100)(125 3100);
WIRE 16 -1 (-500 3550)(-75 3550);
WIRE 16 -1 (-500 1375)(-75 1375);
WIRE 16 -1 (-500 1325)(125 1325);
WIRE 16 -1 (-500 525)(125 525);
WIRE 16 -1 (-500 575)(-75 575);
WIRE 16 -1 (-500 1175)(-75 1175);
WIRE 16 -1 (-500 375)(-75 375);
WIRE 16 -1 (-500 975)(-75 975);
WIRE 16 -1 (-500 1125)(125 1125);
WIRE 16 -1 (-500 925)(125 925);
WIRE 16 -1 (-500 2750)(-75 2750);
WIRE 16 -1 (3900 375)(3300 375);
WIRE 16 -1 (3900 725)(3050 725);
WIRE 16 -1 (3900 525)(3050 525);
WIRE 16 -1 (3900 1125)(3050 1125);
WIRE 16 -1 (3900 975)(3300 975);
WIRE 16 -1 (3900 925)(3050 925);
WIRE 16 -1 (3900 575)(3300 575);
WIRE 16 -1 (3900 775)(3300 775);
WIRE 16 -1 (3900 3150)(3300 3150);
WIRE 16 -1 (3900 2750)(3300 2750);
WIRE 16 -1 (3900 3350)(3300 3350);
WIRE 16 -1 (3900 1775)(3300 1775);
WIRE 16 -1 (3900 1575)(3300 1575);
WIRE 16 -1 (3900 1525)(3050 1525);
WIRE 16 -1 (3900 1325)(3050 1325);
WIRE 16 -1 (3900 325)(3050 325);
WIRE 16 -1 (4050 2950)(4475 2950);
WIRE 16 -1 (4050 3150)(4475 3150);
WIRE 16 -1 (4050 2350)(4475 2350);
WIRE 16 -1 (4050 3550)(4475 3550);
WIRE 16 -1 (4050 2550)(4475 2550);
WIRE 16 -1 (4050 2750)(4475 2750);
WIRE 16 -1 (4050 3350)(4475 3350);
WIRE 16 -1 (4050 3750)(4475 3750);
WIRE 16 -1 (4050 525)(4675 525);
WIRE 16 -1 (4050 725)(4675 725);
WIRE 16 -1 (4050 925)(4675 925);
WIRE 16 -1 (4050 325)(4675 325);
WIRE 16 -1 (4050 1325)(4675 1325);
WIRE 16 -1 (4050 1725)(4675 1725);
WIRE 16 -1 (4050 1525)(4675 1525);
WIRE 16 -1 (4050 1125)(4675 1125);
FORCENOTE
CPU0 PCIE P1 TX
(2475 -325) 0;
DISPLAY LEFT (2475 -325);
DISPLAY 4.148936 (2475 -325);
PAINT WHITE (2475 -325);
FORCENOTE
CPU0 PCIE P0 TX
(-1900 -300) 0;
DISPLAY LEFT (-1900 -300);
DISPLAY 4.148936 (-1900 -300);
PAINT WHITE (-1900 -300);
QUIT
